FILE_TYPE = MACRO_DRAWING;
SET COLOR_WIRE YELLOW;
SET COLOR_PROP ORANGE;
SET COLOR_DOT WHITE;
SET COLOR_ARC YELLOW;
SET COLOR_BODY GREEN;
SET COLOR_NOTE PURPLE;
SET PROP_DISPLAY VALUE;
SET PAGE_NUMBER P105;
FORCEADD OFFPAGE..5
(-8275 1900);
FORCEPROP 2 LAST $XR0 45 
J 0
(-8529 1900);
DISPLAY 0.638298 (-8529 1900);
PAINT MONO (-8529 1900);
FORCEPROP 2 LAST PATH I1
J 0
(-8475 1950);
DISPLAY 1.021277 (-8475 1950);
DISPLAY INVISIBLE (-8475 1950);
FORCEPROP 1 LAST COMMENT_BODY TRUE
J 0
(-8175 1825);
DISPLAY 0.872340 (-8175 1825);
PAINT GREEN (-8175 1825);
DISPLAY INVISIBLE (-8175 1825);
FORCEPROP 1 LAST OFFPAGE TRUE
J 0
(-7950 1775);
DISPLAY 0.872340 (-7950 1775);
PAINT GREEN (-7950 1775);
DISPLAY INVISIBLE (-7950 1775);
FORCEPROP 2 LAST CDS_LIB mstr_standard
J 0
(-8275 1900);
DISPLAY 0.808511 (-8275 1900);
DISPLAY INVISIBLE (-8275 1900);
FORCEADD OFFPAGE..6
(-8275 3550);
FORCEPROP 2 LAST $XR0 45 
J 0
(-8554 3550);
DISPLAY 0.638298 (-8554 3550);
PAINT MONO (-8554 3550);
FORCEPROP 2 LAST PATH I10
J 0
(-8550 3600);
DISPLAY 1.021277 (-8550 3600);
DISPLAY INVISIBLE (-8550 3600);
FORCEPROP 1 LAST COMMENT_BODY TRUE
J 0
(-8175 3475);
DISPLAY 0.872340 (-8175 3475);
PAINT GREEN (-8175 3475);
DISPLAY INVISIBLE (-8175 3475);
FORCEPROP 1 LAST OFFPAGE TRUE
J 0
(-7950 3425);
DISPLAY 0.872340 (-7950 3425);
PAINT GREEN (-7950 3425);
DISPLAY INVISIBLE (-7950 3425);
FORCEPROP 2 LAST CDS_LIB mstr_standard
J 0
(-8275 3550);
DISPLAY 0.723404 (-8275 3550);
PAINT MONO (-8275 3550);
DISPLAY INVISIBLE (-8275 3550);
FORCEADD TAP..1
(-5975 4150);
FORCEPROP 3 LASTPIN (-6025 4150) SIG_NAME M_I_CPU1_SA_DQ<7>
J 0
(-6015 4160);
DISPLAY 0.659574 (-6015 4160);
PAINT MONO (-6015 4160);
DISPLAY INVISIBLE (-6015 4160);
FORCEPROP 1 LASTPIN (-6025 4150) BN 7
J 0
(-6037 4158);
DISPLAY 0.489362 (-6037 4158);
PAINT GREEN (-6037 4158);
FORCEPROP 2 LAST CDS_LIB mstr_standard
J 0
(-5975 4150);
DISPLAY 0.723404 (-5975 4150);
PAINT MONO (-5975 4150);
DISPLAY INVISIBLE (-5975 4150);
FORCEPROP 1 LAST BODY_TYPE PLUMBING
J 0
(-5975 4200);
DISPLAY 0.872340 (-5975 4200);
PAINT GREEN (-5975 4200);
DISPLAY INVISIBLE (-5975 4200);
FORCEPROP 1 LAST HDL_TAP TRUE
J 0
(-5650 4025);
DISPLAY 0.872340 (-5650 4025);
DISPLAY INVISIBLE (-5650 4025);
FORCEPROP 1 LAST PATH I100
J 0
(-5977 4150);
DISPLAY 0.872340 (-5977 4150);
PAINT GREEN (-5977 4150);
DISPLAY INVISIBLE (-5977 4150);
FORCEADD TAP..1
(-5975 4300);
FORCEPROP 3 LASTPIN (-6025 4300) SIG_NAME M_I_CPU1_SA_DQ<10>
J 0
(-6015 4310);
DISPLAY 0.659574 (-6015 4310);
PAINT MONO (-6015 4310);
DISPLAY INVISIBLE (-6015 4310);
FORCEPROP 1 LASTPIN (-6025 4300) BN 10
J 0
(-6037 4308);
DISPLAY 0.489362 (-6037 4308);
PAINT GREEN (-6037 4308);
FORCEPROP 2 LAST CDS_LIB mstr_standard
J 0
(-5975 4300);
DISPLAY 0.723404 (-5975 4300);
PAINT MONO (-5975 4300);
DISPLAY INVISIBLE (-5975 4300);
FORCEPROP 1 LAST BODY_TYPE PLUMBING
J 0
(-5975 4350);
DISPLAY 0.872340 (-5975 4350);
PAINT GREEN (-5975 4350);
DISPLAY INVISIBLE (-5975 4350);
FORCEPROP 1 LAST HDL_TAP TRUE
J 0
(-5650 4175);
DISPLAY 0.872340 (-5650 4175);
DISPLAY INVISIBLE (-5650 4175);
FORCEPROP 1 LAST PATH I101
J 0
(-5977 4300);
DISPLAY 0.872340 (-5977 4300);
PAINT GREEN (-5977 4300);
DISPLAY INVISIBLE (-5977 4300);
FORCEADD TAP..1
(-5975 4250);
FORCEPROP 3 LASTPIN (-6025 4250) SIG_NAME M_I_CPU1_SA_DQ<9>
J 0
(-6015 4260);
DISPLAY 0.659574 (-6015 4260);
PAINT MONO (-6015 4260);
DISPLAY INVISIBLE (-6015 4260);
FORCEPROP 1 LASTPIN (-6025 4250) BN 9
J 0
(-6037 4258);
DISPLAY 0.489362 (-6037 4258);
PAINT GREEN (-6037 4258);
FORCEPROP 2 LAST CDS_LIB mstr_standard
J 0
(-5975 4250);
DISPLAY 0.723404 (-5975 4250);
PAINT MONO (-5975 4250);
DISPLAY INVISIBLE (-5975 4250);
FORCEPROP 1 LAST BODY_TYPE PLUMBING
J 0
(-5975 4300);
DISPLAY 0.872340 (-5975 4300);
PAINT GREEN (-5975 4300);
DISPLAY INVISIBLE (-5975 4300);
FORCEPROP 1 LAST HDL_TAP TRUE
J 0
(-5650 4125);
DISPLAY 0.872340 (-5650 4125);
DISPLAY INVISIBLE (-5650 4125);
FORCEPROP 1 LAST PATH I102
J 0
(-5977 4250);
DISPLAY 0.872340 (-5977 4250);
PAINT GREEN (-5977 4250);
DISPLAY INVISIBLE (-5977 4250);
FORCEADD TAP..1
(-5975 4200);
FORCEPROP 3 LASTPIN (-6025 4200) SIG_NAME M_I_CPU1_SA_DQ<8>
J 0
(-6015 4210);
DISPLAY 0.659574 (-6015 4210);
PAINT MONO (-6015 4210);
DISPLAY INVISIBLE (-6015 4210);
FORCEPROP 1 LASTPIN (-6025 4200) BN 8
J 0
(-6037 4208);
DISPLAY 0.489362 (-6037 4208);
PAINT GREEN (-6037 4208);
FORCEPROP 2 LAST CDS_LIB mstr_standard
J 0
(-5975 4200);
DISPLAY 0.723404 (-5975 4200);
PAINT MONO (-5975 4200);
DISPLAY INVISIBLE (-5975 4200);
FORCEPROP 1 LAST BODY_TYPE PLUMBING
J 0
(-5975 4250);
DISPLAY 0.872340 (-5975 4250);
PAINT GREEN (-5975 4250);
DISPLAY INVISIBLE (-5975 4250);
FORCEPROP 1 LAST HDL_TAP TRUE
J 0
(-5650 4075);
DISPLAY 0.872340 (-5650 4075);
DISPLAY INVISIBLE (-5650 4075);
FORCEPROP 1 LAST PATH I103
J 0
(-5977 4200);
DISPLAY 0.872340 (-5977 4200);
PAINT GREEN (-5977 4200);
DISPLAY INVISIBLE (-5977 4200);
FORCEADD TAP..1
(-5975 4350);
FORCEPROP 3 LASTPIN (-6025 4350) SIG_NAME M_I_CPU1_SA_DQ<11>
J 0
(-6015 4360);
DISPLAY 0.659574 (-6015 4360);
PAINT MONO (-6015 4360);
DISPLAY INVISIBLE (-6015 4360);
FORCEPROP 1 LASTPIN (-6025 4350) BN 11
J 0
(-6037 4358);
DISPLAY 0.489362 (-6037 4358);
PAINT GREEN (-6037 4358);
FORCEPROP 2 LAST CDS_LIB mstr_standard
J 0
(-5975 4350);
DISPLAY 0.723404 (-5975 4350);
PAINT MONO (-5975 4350);
DISPLAY INVISIBLE (-5975 4350);
FORCEPROP 1 LAST BODY_TYPE PLUMBING
J 0
(-5975 4400);
DISPLAY 0.872340 (-5975 4400);
PAINT GREEN (-5975 4400);
DISPLAY INVISIBLE (-5975 4400);
FORCEPROP 1 LAST HDL_TAP TRUE
J 0
(-5650 4225);
DISPLAY 0.872340 (-5650 4225);
DISPLAY INVISIBLE (-5650 4225);
FORCEPROP 1 LAST PATH I104
J 0
(-5977 4350);
DISPLAY 0.872340 (-5977 4350);
PAINT GREEN (-5977 4350);
DISPLAY INVISIBLE (-5977 4350);
FORCEADD TAP..1
(-5975 4400);
FORCEPROP 3 LASTPIN (-6025 4400) SIG_NAME M_I_CPU1_SA_DQ<12>
J 0
(-6015 4410);
DISPLAY 0.659574 (-6015 4410);
PAINT MONO (-6015 4410);
DISPLAY INVISIBLE (-6015 4410);
FORCEPROP 1 LASTPIN (-6025 4400) BN 12
J 0
(-6037 4408);
DISPLAY 0.489362 (-6037 4408);
PAINT GREEN (-6037 4408);
FORCEPROP 2 LAST CDS_LIB mstr_standard
J 0
(-5975 4400);
DISPLAY 0.723404 (-5975 4400);
PAINT MONO (-5975 4400);
DISPLAY INVISIBLE (-5975 4400);
FORCEPROP 1 LAST BODY_TYPE PLUMBING
J 0
(-5975 4450);
DISPLAY 0.872340 (-5975 4450);
PAINT GREEN (-5975 4450);
DISPLAY INVISIBLE (-5975 4450);
FORCEPROP 1 LAST HDL_TAP TRUE
J 0
(-5650 4275);
DISPLAY 0.872340 (-5650 4275);
DISPLAY INVISIBLE (-5650 4275);
FORCEPROP 1 LAST PATH I105
J 0
(-5977 4400);
DISPLAY 0.872340 (-5977 4400);
PAINT GREEN (-5977 4400);
DISPLAY INVISIBLE (-5977 4400);
FORCEADD TAP..1
(-5975 4450);
FORCEPROP 3 LASTPIN (-6025 4450) SIG_NAME M_I_CPU1_SA_DQ<13>
J 0
(-6015 4460);
DISPLAY 0.659574 (-6015 4460);
PAINT MONO (-6015 4460);
DISPLAY INVISIBLE (-6015 4460);
FORCEPROP 1 LASTPIN (-6025 4450) BN 13
J 0
(-6037 4458);
DISPLAY 0.489362 (-6037 4458);
PAINT GREEN (-6037 4458);
FORCEPROP 2 LAST CDS_LIB mstr_standard
J 0
(-5975 4450);
DISPLAY 0.723404 (-5975 4450);
PAINT MONO (-5975 4450);
DISPLAY INVISIBLE (-5975 4450);
FORCEPROP 1 LAST BODY_TYPE PLUMBING
J 0
(-5975 4500);
DISPLAY 0.872340 (-5975 4500);
PAINT GREEN (-5975 4500);
DISPLAY INVISIBLE (-5975 4500);
FORCEPROP 1 LAST HDL_TAP TRUE
J 0
(-5650 4325);
DISPLAY 0.872340 (-5650 4325);
DISPLAY INVISIBLE (-5650 4325);
FORCEPROP 1 LAST PATH I106
J 0
(-5977 4450);
DISPLAY 0.872340 (-5977 4450);
PAINT GREEN (-5977 4450);
DISPLAY INVISIBLE (-5977 4450);
FORCEADD TAP..1
(-5975 4500);
FORCEPROP 3 LASTPIN (-6025 4500) SIG_NAME M_I_CPU1_SA_DQ<14>
J 0
(-6015 4510);
DISPLAY 0.659574 (-6015 4510);
PAINT MONO (-6015 4510);
DISPLAY INVISIBLE (-6015 4510);
FORCEPROP 1 LASTPIN (-6025 4500) BN 14
J 0
(-6037 4508);
DISPLAY 0.489362 (-6037 4508);
PAINT GREEN (-6037 4508);
FORCEPROP 2 LAST CDS_LIB mstr_standard
J 0
(-5975 4500);
DISPLAY 0.723404 (-5975 4500);
PAINT MONO (-5975 4500);
DISPLAY INVISIBLE (-5975 4500);
FORCEPROP 1 LAST BODY_TYPE PLUMBING
J 0
(-5975 4550);
DISPLAY 0.872340 (-5975 4550);
PAINT GREEN (-5975 4550);
DISPLAY INVISIBLE (-5975 4550);
FORCEPROP 1 LAST HDL_TAP TRUE
J 0
(-5650 4375);
DISPLAY 0.872340 (-5650 4375);
DISPLAY INVISIBLE (-5650 4375);
FORCEPROP 1 LAST PATH I107
J 0
(-5977 4500);
DISPLAY 0.872340 (-5977 4500);
PAINT GREEN (-5977 4500);
DISPLAY INVISIBLE (-5977 4500);
FORCEADD TAP..1
(-5975 4550);
FORCEPROP 3 LASTPIN (-6025 4550) SIG_NAME M_I_CPU1_SA_DQ<15>
J 0
(-6015 4560);
DISPLAY 0.659574 (-6015 4560);
PAINT MONO (-6015 4560);
DISPLAY INVISIBLE (-6015 4560);
FORCEPROP 1 LASTPIN (-6025 4550) BN 15
J 0
(-6037 4558);
DISPLAY 0.489362 (-6037 4558);
PAINT GREEN (-6037 4558);
FORCEPROP 2 LAST CDS_LIB mstr_standard
J 0
(-5975 4550);
DISPLAY 0.723404 (-5975 4550);
PAINT MONO (-5975 4550);
DISPLAY INVISIBLE (-5975 4550);
FORCEPROP 1 LAST BODY_TYPE PLUMBING
J 0
(-5975 4600);
DISPLAY 0.872340 (-5975 4600);
PAINT GREEN (-5975 4600);
DISPLAY INVISIBLE (-5975 4600);
FORCEPROP 1 LAST HDL_TAP TRUE
J 0
(-5650 4425);
DISPLAY 0.872340 (-5650 4425);
DISPLAY INVISIBLE (-5650 4425);
FORCEPROP 1 LAST PATH I108
J 0
(-5977 4550);
DISPLAY 0.872340 (-5977 4550);
PAINT GREEN (-5977 4550);
DISPLAY INVISIBLE (-5977 4550);
FORCEADD TAP..1
(-5975 4650);
FORCEPROP 3 LASTPIN (-6025 4650) SIG_NAME M_I_CPU1_SA_DQ<17>
J 0
(-6015 4660);
DISPLAY 0.659574 (-6015 4660);
PAINT MONO (-6015 4660);
DISPLAY INVISIBLE (-6015 4660);
FORCEPROP 1 LASTPIN (-6025 4650) BN 17
J 0
(-6037 4658);
DISPLAY 0.489362 (-6037 4658);
PAINT GREEN (-6037 4658);
FORCEPROP 2 LAST CDS_LIB mstr_standard
J 0
(-5975 4650);
DISPLAY 0.723404 (-5975 4650);
PAINT MONO (-5975 4650);
DISPLAY INVISIBLE (-5975 4650);
FORCEPROP 1 LAST BODY_TYPE PLUMBING
J 0
(-5975 4700);
DISPLAY 0.872340 (-5975 4700);
PAINT GREEN (-5975 4700);
DISPLAY INVISIBLE (-5975 4700);
FORCEPROP 1 LAST HDL_TAP TRUE
J 0
(-5650 4525);
DISPLAY 0.872340 (-5650 4525);
DISPLAY INVISIBLE (-5650 4525);
FORCEPROP 1 LAST PATH I109
J 0
(-5977 4650);
DISPLAY 0.872340 (-5977 4650);
PAINT GREEN (-5977 4650);
DISPLAY INVISIBLE (-5977 4650);
FORCEADD OFFPAGE..6
(-8275 4000);
FORCEPROP 2 LAST $XR0 45 
J 0
(-8554 4000);
DISPLAY 0.638298 (-8554 4000);
PAINT MONO (-8554 4000);
FORCEPROP 2 LAST PATH I11
J 0
(-8550 4050);
DISPLAY 1.021277 (-8550 4050);
DISPLAY INVISIBLE (-8550 4050);
FORCEPROP 1 LAST COMMENT_BODY TRUE
J 0
(-8175 3925);
DISPLAY 0.872340 (-8175 3925);
PAINT GREEN (-8175 3925);
DISPLAY INVISIBLE (-8175 3925);
FORCEPROP 1 LAST OFFPAGE TRUE
J 0
(-7950 3875);
DISPLAY 0.872340 (-7950 3875);
PAINT GREEN (-7950 3875);
DISPLAY INVISIBLE (-7950 3875);
FORCEPROP 2 LAST CDS_LIB mstr_standard
J 0
(-8275 4000);
DISPLAY 0.723404 (-8275 4000);
PAINT MONO (-8275 4000);
DISPLAY INVISIBLE (-8275 4000);
FORCEADD TAP..1
(-5975 4600);
FORCEPROP 3 LASTPIN (-6025 4600) SIG_NAME M_I_CPU1_SA_DQ<16>
J 0
(-6015 4610);
DISPLAY 0.659574 (-6015 4610);
PAINT MONO (-6015 4610);
DISPLAY INVISIBLE (-6015 4610);
FORCEPROP 1 LASTPIN (-6025 4600) BN 16
J 0
(-6037 4608);
DISPLAY 0.489362 (-6037 4608);
PAINT GREEN (-6037 4608);
FORCEPROP 2 LAST CDS_LIB mstr_standard
J 0
(-5975 4600);
DISPLAY 0.723404 (-5975 4600);
PAINT MONO (-5975 4600);
DISPLAY INVISIBLE (-5975 4600);
FORCEPROP 1 LAST BODY_TYPE PLUMBING
J 0
(-5975 4650);
DISPLAY 0.872340 (-5975 4650);
PAINT GREEN (-5975 4650);
DISPLAY INVISIBLE (-5975 4650);
FORCEPROP 1 LAST HDL_TAP TRUE
J 0
(-5650 4475);
DISPLAY 0.872340 (-5650 4475);
DISPLAY INVISIBLE (-5650 4475);
FORCEPROP 1 LAST PATH I110
J 0
(-5977 4600);
DISPLAY 0.872340 (-5977 4600);
PAINT GREEN (-5977 4600);
DISPLAY INVISIBLE (-5977 4600);
FORCEADD TAP..1
(-5975 4800);
FORCEPROP 3 LASTPIN (-6025 4800) SIG_NAME M_I_CPU1_SA_DQ<20>
J 0
(-6015 4810);
DISPLAY 0.659574 (-6015 4810);
PAINT MONO (-6015 4810);
DISPLAY INVISIBLE (-6015 4810);
FORCEPROP 1 LASTPIN (-6025 4800) BN 20
J 0
(-6037 4808);
DISPLAY 0.489362 (-6037 4808);
PAINT GREEN (-6037 4808);
FORCEPROP 2 LAST CDS_LIB mstr_standard
J 0
(-5975 4800);
DISPLAY 0.723404 (-5975 4800);
PAINT MONO (-5975 4800);
DISPLAY INVISIBLE (-5975 4800);
FORCEPROP 1 LAST BODY_TYPE PLUMBING
J 0
(-5975 4850);
DISPLAY 0.872340 (-5975 4850);
PAINT GREEN (-5975 4850);
DISPLAY INVISIBLE (-5975 4850);
FORCEPROP 1 LAST HDL_TAP TRUE
J 0
(-5650 4675);
DISPLAY 0.872340 (-5650 4675);
DISPLAY INVISIBLE (-5650 4675);
FORCEPROP 1 LAST PATH I111
J 0
(-5977 4800);
DISPLAY 0.872340 (-5977 4800);
PAINT GREEN (-5977 4800);
DISPLAY INVISIBLE (-5977 4800);
FORCEADD TAP..1
(-5975 4750);
FORCEPROP 3 LASTPIN (-6025 4750) SIG_NAME M_I_CPU1_SA_DQ<19>
J 0
(-6015 4760);
DISPLAY 0.659574 (-6015 4760);
PAINT MONO (-6015 4760);
DISPLAY INVISIBLE (-6015 4760);
FORCEPROP 1 LASTPIN (-6025 4750) BN 19
J 0
(-6037 4758);
DISPLAY 0.489362 (-6037 4758);
PAINT GREEN (-6037 4758);
FORCEPROP 2 LAST CDS_LIB mstr_standard
J 0
(-5975 4750);
DISPLAY 0.723404 (-5975 4750);
PAINT MONO (-5975 4750);
DISPLAY INVISIBLE (-5975 4750);
FORCEPROP 1 LAST BODY_TYPE PLUMBING
J 0
(-5975 4800);
DISPLAY 0.872340 (-5975 4800);
PAINT GREEN (-5975 4800);
DISPLAY INVISIBLE (-5975 4800);
FORCEPROP 1 LAST HDL_TAP TRUE
J 0
(-5650 4625);
DISPLAY 0.872340 (-5650 4625);
DISPLAY INVISIBLE (-5650 4625);
FORCEPROP 1 LAST PATH I112
J 0
(-5977 4750);
DISPLAY 0.872340 (-5977 4750);
PAINT GREEN (-5977 4750);
DISPLAY INVISIBLE (-5977 4750);
FORCEADD TAP..1
(-5975 4700);
FORCEPROP 3 LASTPIN (-6025 4700) SIG_NAME M_I_CPU1_SA_DQ<18>
J 0
(-6015 4710);
DISPLAY 0.659574 (-6015 4710);
PAINT MONO (-6015 4710);
DISPLAY INVISIBLE (-6015 4710);
FORCEPROP 1 LASTPIN (-6025 4700) BN 18
J 0
(-6037 4708);
DISPLAY 0.489362 (-6037 4708);
PAINT GREEN (-6037 4708);
FORCEPROP 2 LAST CDS_LIB mstr_standard
J 0
(-5975 4700);
DISPLAY 0.723404 (-5975 4700);
PAINT MONO (-5975 4700);
DISPLAY INVISIBLE (-5975 4700);
FORCEPROP 1 LAST BODY_TYPE PLUMBING
J 0
(-5975 4750);
DISPLAY 0.872340 (-5975 4750);
PAINT GREEN (-5975 4750);
DISPLAY INVISIBLE (-5975 4750);
FORCEPROP 1 LAST HDL_TAP TRUE
J 0
(-5650 4575);
DISPLAY 0.872340 (-5650 4575);
DISPLAY INVISIBLE (-5650 4575);
FORCEPROP 1 LAST PATH I113
J 0
(-5977 4700);
DISPLAY 0.872340 (-5977 4700);
PAINT GREEN (-5977 4700);
DISPLAY INVISIBLE (-5977 4700);
FORCEADD TAP..1
(-5975 4900);
FORCEPROP 3 LASTPIN (-6025 4900) SIG_NAME M_I_CPU1_SA_DQ<22>
J 0
(-6015 4910);
DISPLAY 0.659574 (-6015 4910);
PAINT MONO (-6015 4910);
DISPLAY INVISIBLE (-6015 4910);
FORCEPROP 1 LASTPIN (-6025 4900) BN 22
J 0
(-6037 4908);
DISPLAY 0.489362 (-6037 4908);
PAINT GREEN (-6037 4908);
FORCEPROP 2 LAST CDS_LIB mstr_standard
J 0
(-5975 4900);
DISPLAY 0.723404 (-5975 4900);
PAINT MONO (-5975 4900);
DISPLAY INVISIBLE (-5975 4900);
FORCEPROP 1 LAST BODY_TYPE PLUMBING
J 0
(-5975 4950);
DISPLAY 0.872340 (-5975 4950);
PAINT GREEN (-5975 4950);
DISPLAY INVISIBLE (-5975 4950);
FORCEPROP 1 LAST HDL_TAP TRUE
J 0
(-5650 4775);
DISPLAY 0.872340 (-5650 4775);
DISPLAY INVISIBLE (-5650 4775);
FORCEPROP 1 LAST PATH I114
J 0
(-5977 4900);
DISPLAY 0.872340 (-5977 4900);
PAINT GREEN (-5977 4900);
DISPLAY INVISIBLE (-5977 4900);
FORCEADD TAP..1
(-5975 4850);
FORCEPROP 3 LASTPIN (-6025 4850) SIG_NAME M_I_CPU1_SA_DQ<21>
J 0
(-6015 4860);
DISPLAY 0.659574 (-6015 4860);
PAINT MONO (-6015 4860);
DISPLAY INVISIBLE (-6015 4860);
FORCEPROP 1 LASTPIN (-6025 4850) BN 21
J 0
(-6037 4858);
DISPLAY 0.489362 (-6037 4858);
PAINT GREEN (-6037 4858);
FORCEPROP 2 LAST CDS_LIB mstr_standard
J 0
(-5975 4850);
DISPLAY 0.723404 (-5975 4850);
PAINT MONO (-5975 4850);
DISPLAY INVISIBLE (-5975 4850);
FORCEPROP 1 LAST BODY_TYPE PLUMBING
J 0
(-5975 4900);
DISPLAY 0.872340 (-5975 4900);
PAINT GREEN (-5975 4900);
DISPLAY INVISIBLE (-5975 4900);
FORCEPROP 1 LAST HDL_TAP TRUE
J 0
(-5650 4725);
DISPLAY 0.872340 (-5650 4725);
DISPLAY INVISIBLE (-5650 4725);
FORCEPROP 1 LAST PATH I115
J 0
(-5977 4850);
DISPLAY 0.872340 (-5977 4850);
PAINT GREEN (-5977 4850);
DISPLAY INVISIBLE (-5977 4850);
FORCEADD TAP..1
(-5975 5050);
FORCEPROP 3 LASTPIN (-6025 5050) SIG_NAME M_I_CPU1_SA_DQ<25>
J 0
(-6015 5060);
DISPLAY 0.659574 (-6015 5060);
PAINT MONO (-6015 5060);
DISPLAY INVISIBLE (-6015 5060);
FORCEPROP 1 LASTPIN (-6025 5050) BN 25
J 0
(-6037 5058);
DISPLAY 0.489362 (-6037 5058);
PAINT GREEN (-6037 5058);
FORCEPROP 2 LAST CDS_LIB mstr_standard
J 0
(-5975 5050);
DISPLAY 0.723404 (-5975 5050);
PAINT MONO (-5975 5050);
DISPLAY INVISIBLE (-5975 5050);
FORCEPROP 1 LAST BODY_TYPE PLUMBING
J 0
(-5975 5100);
DISPLAY 0.872340 (-5975 5100);
PAINT GREEN (-5975 5100);
DISPLAY INVISIBLE (-5975 5100);
FORCEPROP 1 LAST HDL_TAP TRUE
J 0
(-5650 4925);
DISPLAY 0.872340 (-5650 4925);
DISPLAY INVISIBLE (-5650 4925);
FORCEPROP 1 LAST PATH I116
J 0
(-5977 5050);
DISPLAY 0.872340 (-5977 5050);
PAINT GREEN (-5977 5050);
DISPLAY INVISIBLE (-5977 5050);
FORCEADD TAP..1
(-5975 5000);
FORCEPROP 3 LASTPIN (-6025 5000) SIG_NAME M_I_CPU1_SA_DQ<24>
J 0
(-6015 5010);
DISPLAY 0.659574 (-6015 5010);
PAINT MONO (-6015 5010);
DISPLAY INVISIBLE (-6015 5010);
FORCEPROP 1 LASTPIN (-6025 5000) BN 24
J 0
(-6037 5008);
DISPLAY 0.489362 (-6037 5008);
PAINT GREEN (-6037 5008);
FORCEPROP 2 LAST CDS_LIB mstr_standard
J 0
(-5975 5000);
DISPLAY 0.723404 (-5975 5000);
PAINT MONO (-5975 5000);
DISPLAY INVISIBLE (-5975 5000);
FORCEPROP 1 LAST BODY_TYPE PLUMBING
J 0
(-5975 5050);
DISPLAY 0.872340 (-5975 5050);
PAINT GREEN (-5975 5050);
DISPLAY INVISIBLE (-5975 5050);
FORCEPROP 1 LAST HDL_TAP TRUE
J 0
(-5650 4875);
DISPLAY 0.872340 (-5650 4875);
DISPLAY INVISIBLE (-5650 4875);
FORCEPROP 1 LAST PATH I117
J 0
(-5977 5000);
DISPLAY 0.872340 (-5977 5000);
PAINT GREEN (-5977 5000);
DISPLAY INVISIBLE (-5977 5000);
FORCEADD TAP..1
(-5975 4950);
FORCEPROP 3 LASTPIN (-6025 4950) SIG_NAME M_I_CPU1_SA_DQ<23>
J 0
(-6015 4960);
DISPLAY 0.659574 (-6015 4960);
PAINT MONO (-6015 4960);
DISPLAY INVISIBLE (-6015 4960);
FORCEPROP 1 LASTPIN (-6025 4950) BN 23
J 0
(-6037 4958);
DISPLAY 0.489362 (-6037 4958);
PAINT GREEN (-6037 4958);
FORCEPROP 2 LAST CDS_LIB mstr_standard
J 0
(-5975 4950);
DISPLAY 0.723404 (-5975 4950);
PAINT MONO (-5975 4950);
DISPLAY INVISIBLE (-5975 4950);
FORCEPROP 1 LAST BODY_TYPE PLUMBING
J 0
(-5975 5000);
DISPLAY 0.872340 (-5975 5000);
PAINT GREEN (-5975 5000);
DISPLAY INVISIBLE (-5975 5000);
FORCEPROP 1 LAST HDL_TAP TRUE
J 0
(-5650 4825);
DISPLAY 0.872340 (-5650 4825);
DISPLAY INVISIBLE (-5650 4825);
FORCEPROP 1 LAST PATH I118
J 0
(-5977 4950);
DISPLAY 0.872340 (-5977 4950);
PAINT GREEN (-5977 4950);
DISPLAY INVISIBLE (-5977 4950);
FORCEADD TAP..1
(-5975 5150);
FORCEPROP 3 LASTPIN (-6025 5150) SIG_NAME M_I_CPU1_SA_DQ<27>
J 0
(-6015 5160);
DISPLAY 0.659574 (-6015 5160);
PAINT MONO (-6015 5160);
DISPLAY INVISIBLE (-6015 5160);
FORCEPROP 1 LASTPIN (-6025 5150) BN 27
J 0
(-6037 5158);
DISPLAY 0.489362 (-6037 5158);
PAINT GREEN (-6037 5158);
FORCEPROP 2 LAST CDS_LIB mstr_standard
J 0
(-5975 5150);
DISPLAY 0.723404 (-5975 5150);
PAINT MONO (-5975 5150);
DISPLAY INVISIBLE (-5975 5150);
FORCEPROP 1 LAST BODY_TYPE PLUMBING
J 0
(-5975 5200);
DISPLAY 0.872340 (-5975 5200);
PAINT GREEN (-5975 5200);
DISPLAY INVISIBLE (-5975 5200);
FORCEPROP 1 LAST HDL_TAP TRUE
J 0
(-5650 5025);
DISPLAY 0.872340 (-5650 5025);
DISPLAY INVISIBLE (-5650 5025);
FORCEPROP 1 LAST PATH I119
J 0
(-5977 5150);
DISPLAY 0.872340 (-5977 5150);
PAINT GREEN (-5977 5150);
DISPLAY INVISIBLE (-5977 5150);
FORCEADD OFFPAGE..1
(-8275 4050);
FORCEPROP 2 LAST $XR0 45 
J 0
(-8526 4050);
DISPLAY 0.638298 (-8526 4050);
PAINT MONO (-8526 4050);
FORCEPROP 2 LAST PATH I12
J 0
(-8525 4100);
DISPLAY 1.021277 (-8525 4100);
DISPLAY INVISIBLE (-8525 4100);
FORCEPROP 1 LAST COMMENT_BODY TRUE
J 0
(-8150 3950);
DISPLAY 0.872340 (-8150 3950);
PAINT GREEN (-8150 3950);
DISPLAY INVISIBLE (-8150 3950);
FORCEPROP 1 LAST OFFPAGE TRUE
J 0
(-7950 3925);
DISPLAY 0.872340 (-7950 3925);
PAINT GREEN (-7950 3925);
DISPLAY INVISIBLE (-7950 3925);
FORCEPROP 2 LAST CDS_LIB mstr_standard
J 0
(-8275 4050);
DISPLAY 0.808511 (-8275 4050);
DISPLAY INVISIBLE (-8275 4050);
FORCEADD TAP..1
(-5975 5200);
FORCEPROP 3 LASTPIN (-6025 5200) SIG_NAME M_I_CPU1_SA_DQ<28>
J 0
(-6015 5210);
DISPLAY 0.659574 (-6015 5210);
PAINT MONO (-6015 5210);
DISPLAY INVISIBLE (-6015 5210);
FORCEPROP 1 LASTPIN (-6025 5200) BN 28
J 0
(-6037 5208);
DISPLAY 0.489362 (-6037 5208);
PAINT GREEN (-6037 5208);
FORCEPROP 2 LAST CDS_LIB mstr_standard
J 0
(-5975 5200);
DISPLAY 0.723404 (-5975 5200);
PAINT MONO (-5975 5200);
DISPLAY INVISIBLE (-5975 5200);
FORCEPROP 1 LAST BODY_TYPE PLUMBING
J 0
(-5975 5250);
DISPLAY 0.872340 (-5975 5250);
PAINT GREEN (-5975 5250);
DISPLAY INVISIBLE (-5975 5250);
FORCEPROP 1 LAST HDL_TAP TRUE
J 0
(-5650 5075);
DISPLAY 0.872340 (-5650 5075);
DISPLAY INVISIBLE (-5650 5075);
FORCEPROP 1 LAST PATH I120
J 0
(-5977 5200);
DISPLAY 0.872340 (-5977 5200);
PAINT GREEN (-5977 5200);
DISPLAY INVISIBLE (-5977 5200);
FORCEADD TAP..1
(-5975 5100);
FORCEPROP 3 LASTPIN (-6025 5100) SIG_NAME M_I_CPU1_SA_DQ<26>
J 0
(-6015 5110);
DISPLAY 0.659574 (-6015 5110);
PAINT MONO (-6015 5110);
DISPLAY INVISIBLE (-6015 5110);
FORCEPROP 1 LASTPIN (-6025 5100) BN 26
J 0
(-6037 5108);
DISPLAY 0.489362 (-6037 5108);
PAINT GREEN (-6037 5108);
FORCEPROP 2 LAST CDS_LIB mstr_standard
J 0
(-5975 5100);
DISPLAY 0.723404 (-5975 5100);
PAINT MONO (-5975 5100);
DISPLAY INVISIBLE (-5975 5100);
FORCEPROP 1 LAST BODY_TYPE PLUMBING
J 0
(-5975 5150);
DISPLAY 0.872340 (-5975 5150);
PAINT GREEN (-5975 5150);
DISPLAY INVISIBLE (-5975 5150);
FORCEPROP 1 LAST HDL_TAP TRUE
J 0
(-5650 4975);
DISPLAY 0.872340 (-5650 4975);
DISPLAY INVISIBLE (-5650 4975);
FORCEPROP 1 LAST PATH I121
J 0
(-5977 5100);
DISPLAY 0.872340 (-5977 5100);
PAINT GREEN (-5977 5100);
DISPLAY INVISIBLE (-5977 5100);
FORCEADD TAP..1
(-5975 5300);
FORCEPROP 3 LASTPIN (-6025 5300) SIG_NAME M_I_CPU1_SA_DQ<30>
J 0
(-6015 5310);
DISPLAY 0.659574 (-6015 5310);
PAINT MONO (-6015 5310);
DISPLAY INVISIBLE (-6015 5310);
FORCEPROP 1 LASTPIN (-6025 5300) BN 30
J 0
(-6037 5308);
DISPLAY 0.489362 (-6037 5308);
PAINT GREEN (-6037 5308);
FORCEPROP 2 LAST CDS_LIB mstr_standard
J 0
(-5975 5300);
DISPLAY 0.723404 (-5975 5300);
PAINT MONO (-5975 5300);
DISPLAY INVISIBLE (-5975 5300);
FORCEPROP 1 LAST BODY_TYPE PLUMBING
J 0
(-5975 5350);
DISPLAY 0.872340 (-5975 5350);
PAINT GREEN (-5975 5350);
DISPLAY INVISIBLE (-5975 5350);
FORCEPROP 1 LAST HDL_TAP TRUE
J 0
(-5650 5175);
DISPLAY 0.872340 (-5650 5175);
DISPLAY INVISIBLE (-5650 5175);
FORCEPROP 1 LAST PATH I122
J 0
(-5977 5300);
DISPLAY 0.872340 (-5977 5300);
PAINT GREEN (-5977 5300);
DISPLAY INVISIBLE (-5977 5300);
FORCEADD TAP..1
(-5975 5250);
FORCEPROP 3 LASTPIN (-6025 5250) SIG_NAME M_I_CPU1_SA_DQ<29>
J 0
(-6015 5260);
DISPLAY 0.659574 (-6015 5260);
PAINT MONO (-6015 5260);
DISPLAY INVISIBLE (-6015 5260);
FORCEPROP 1 LASTPIN (-6025 5250) BN 29
J 0
(-6037 5258);
DISPLAY 0.489362 (-6037 5258);
PAINT GREEN (-6037 5258);
FORCEPROP 2 LAST CDS_LIB mstr_standard
J 0
(-5975 5250);
DISPLAY 0.723404 (-5975 5250);
PAINT MONO (-5975 5250);
DISPLAY INVISIBLE (-5975 5250);
FORCEPROP 1 LAST BODY_TYPE PLUMBING
J 0
(-5975 5300);
DISPLAY 0.872340 (-5975 5300);
PAINT GREEN (-5975 5300);
DISPLAY INVISIBLE (-5975 5300);
FORCEPROP 1 LAST HDL_TAP TRUE
J 0
(-5650 5125);
DISPLAY 0.872340 (-5650 5125);
DISPLAY INVISIBLE (-5650 5125);
FORCEPROP 1 LAST PATH I123
J 0
(-5977 5250);
DISPLAY 0.872340 (-5977 5250);
PAINT GREEN (-5977 5250);
DISPLAY INVISIBLE (-5977 5250);
FORCEADD TAP..1
(-5975 5350);
FORCEPROP 3 LASTPIN (-6025 5350) SIG_NAME M_I_CPU1_SA_DQ<31>
J 0
(-6015 5360);
DISPLAY 0.659574 (-6015 5360);
PAINT MONO (-6015 5360);
DISPLAY INVISIBLE (-6015 5360);
FORCEPROP 1 LASTPIN (-6025 5350) BN 31
J 0
(-6037 5358);
DISPLAY 0.489362 (-6037 5358);
PAINT GREEN (-6037 5358);
FORCEPROP 2 LAST CDS_LIB mstr_standard
J 0
(-5975 5350);
DISPLAY 0.723404 (-5975 5350);
PAINT MONO (-5975 5350);
DISPLAY INVISIBLE (-5975 5350);
FORCEPROP 1 LAST BODY_TYPE PLUMBING
J 0
(-5975 5400);
DISPLAY 0.872340 (-5975 5400);
PAINT GREEN (-5975 5400);
DISPLAY INVISIBLE (-5975 5400);
FORCEPROP 1 LAST HDL_TAP TRUE
J 0
(-5650 5225);
DISPLAY 0.872340 (-5650 5225);
DISPLAY INVISIBLE (-5650 5225);
FORCEPROP 1 LAST PATH I124
J 0
(-5977 5350);
DISPLAY 0.872340 (-5977 5350);
PAINT GREEN (-5977 5350);
DISPLAY INVISIBLE (-5977 5350);
FORCEADD OFFPAGE..3
(-5275 5400);
FORCEPROP 2 LAST $XR0 45 
J 0
(-5061 5400);
DISPLAY 0.638298 (-5061 5400);
PAINT MONO (-5061 5400);
FORCEPROP 2 LAST PATH I125
J 0
(-5050 5450);
DISPLAY 1.021277 (-5050 5450);
DISPLAY INVISIBLE (-5050 5450);
FORCEPROP 1 LAST COMMENT_BODY TRUE
J 0
(-5325 5300);
DISPLAY 0.872340 (-5325 5300);
PAINT GREEN (-5325 5300);
DISPLAY INVISIBLE (-5325 5300);
FORCEPROP 1 LAST OFFPAGE TRUE
J 0
(-4950 5275);
DISPLAY 0.872340 (-4950 5275);
PAINT GREEN (-4950 5275);
DISPLAY INVISIBLE (-4950 5275);
FORCEPROP 2 LAST CDS_LIB mstr_standard
J 0
(-5275 5400);
DISPLAY 0.723404 (-5275 5400);
PAINT MONO (-5275 5400);
DISPLAY INVISIBLE (-5275 5400);
FORCEADD OFFPAGE..5
(-7150 1325);
FORCEPROP 2 LAST $XR0 105 
J 0
(-7405 1325);
DISPLAY 0.638298 (-7405 1325);
PAINT MONO (-7405 1325);
FORCEPROP 2 LAST PATH I126
J 0
(-7425 1375);
DISPLAY 1.021277 (-7425 1375);
DISPLAY INVISIBLE (-7425 1375);
FORCEPROP 1 LAST COMMENT_BODY TRUE
J 0
(-7050 1250);
DISPLAY 0.872340 (-7050 1250);
PAINT GREEN (-7050 1250);
DISPLAY INVISIBLE (-7050 1250);
FORCEPROP 1 LAST OFFPAGE TRUE
J 0
(-6825 1200);
DISPLAY 0.872340 (-6825 1200);
PAINT GREEN (-6825 1200);
DISPLAY INVISIBLE (-6825 1200);
FORCEPROP 2 LAST BOM_COST MEM
J 0
(-7225 1400);
DISPLAY 0.808511 (-7225 1400);
DISPLAY INVISIBLE (-7225 1400);
FORCEPROP 2 LAST CDS_LIB mstr_standard
J 0
(-7150 1325);
DISPLAY 0.808511 (-7150 1325);
DISPLAY INVISIBLE (-7150 1325);
FORCEADD GND..1
(-6375 925);
FORCEPROP 3 LASTPIN (-6375 975) SIG_NAME GND\g
J 0
(-6365 985);
DISPLAY 0.659574 (-6365 985);
PAINT MONO (-6365 985);
DISPLAY INVISIBLE (-6365 985);
FORCEPROP 1 LAST SIZE 1B
J 0
(-6300 875);
DISPLAY 0.851064 (-6300 875);
PAINT GREEN (-6300 875);
DISPLAY INVISIBLE (-6300 875);
FORCEPROP 2 LAST CDS_LIB mstr_symbols
J 0
(-6375 925);
DISPLAY 0.808511 (-6375 925);
DISPLAY INVISIBLE (-6375 925);
FORCEPROP 2 LAST BOM_COST MEM
J 0
(-6475 1000);
DISPLAY 0.808511 (-6475 1000);
DISPLAY INVISIBLE (-6475 1000);
FORCEPROP 1 LAST BODY_TYPE PLUMBING
J 0
(-6420 882);
DISPLAY 0.340426 (-6420 882);
PAINT GREEN (-6420 882);
DISPLAY INVISIBLE (-6420 882);
FORCEPROP 1 LAST PATH I127
J 0
(-6300 925);
DISPLAY 0.872340 (-6300 925);
PAINT AQUA (-6300 925);
DISPLAY INVISIBLE (-6300 925);
FORCEPROP 1 LAST VOLTAGE 0.0
J 0
(-6420 882);
DISPLAY 0.723404 (-6420 882);
PAINT SKYBLUE (-6420 882);
DISPLAY INVISIBLE (-6420 882);
FORCEPROP 1 LAST HDL_POWER GND
J 0
(-6375 1075);
DISPLAY 0.851064 (-6375 1075);
PAINT GREEN (-6375 1075);
DISPLAY INVISIBLE (-6375 1075);
FORCEADD Q_RES..2
(-6375 1150);
FORCEPROP 1 LAST LOCATION R775
J 0
(-6330 1275);
DISPLAY 0.489362 (-6330 1275);
PAINT SKYBLUE (-6330 1275);
FORCEPROP 0 LAST $SEC 1
J 0
(-6325 1325);
DISPLAY 0.680851 (-6325 1325);
PAINT MONO (-6325 1325);
DISPLAY INVISIBLE (-6325 1325);
FORCEPROP 0 LAST CDS_SEC 1
J 0
(-6325 1325);
DISPLAY 1.021277 (-6325 1325);
DISPLAY INVISIBLE (-6325 1325);
FORCEPROP 1 LASTPIN (-6375 1250) $PN 1
J 0
(-6370 1212);
DISPLAY 0.489362 (-6370 1212);
PAINT MONO (-6370 1212);
FORCEPROP 1 LASTPIN (-6375 1050) $PN 2
J 0
(-6370 1060);
DISPLAY 0.489362 (-6370 1060);
PAINT MONO (-6370 1060);
FORCEPROP 1 LAST WATTAGE 1/16W
J 0
(-6335 1125);
DISPLAY 0.489362 (-6335 1125);
PAINT SKYBLUE (-6335 1125);
FORCEPROP 1 LAST MATERIAL CHIP
J 0
(-6335 1075);
DISPLAY 0.489362 (-6335 1075);
PAINT SKYBLUE (-6335 1075);
FORCEPROP 1 LAST TOLERANCE 1%
J 0
(-6330 1175);
DISPLAY 0.489362 (-6330 1175);
PAINT SKYBLUE (-6330 1175);
FORCEPROP 1 LAST VALUE 23.2K
J 0
(-6330 1225);
DISPLAY 0.489362 (-6330 1225);
PAINT SKYBLUE (-6330 1225);
FORCEPROP 1 LAST PART_NUMBER TMP_QCS32322FB11
J 0
(-6335 1025);
DISPLAY 0.489362 (-6335 1025);
PAINT SKYBLUE (-6335 1025);
FORCEPROP 1 LAST PACK_TYPE 0402LF
J 0
(-6335 975);
DISPLAY 0.489362 (-6335 975);
PAINT SKYBLUE (-6335 975);
FORCEPROP 2 LAST CDS_LIB pure_quanta
J 0
(-6375 1150);
DISPLAY INVISIBLE (-6375 1150);
FORCEPROP 1 LAST PATH I128
J 0
(-6325 1325);
DISPLAY 0.978723 (-6325 1325);
PAINT WHITE (-6325 1325);
DISPLAY INVISIBLE (-6325 1325);
FORCEADD OFFPAGE..1
(-8275 4250);
FORCEPROP 2 LAST $XR0 45 
J 0
(-8526 4250);
DISPLAY 0.638298 (-8526 4250);
PAINT MONO (-8526 4250);
FORCEPROP 2 LAST PATH I13
J 0
(-8525 4300);
DISPLAY 1.021277 (-8525 4300);
DISPLAY INVISIBLE (-8525 4300);
FORCEPROP 1 LAST COMMENT_BODY TRUE
J 0
(-8150 4150);
DISPLAY 0.872340 (-8150 4150);
PAINT GREEN (-8150 4150);
DISPLAY INVISIBLE (-8150 4150);
FORCEPROP 1 LAST OFFPAGE TRUE
J 0
(-7950 4125);
DISPLAY 0.872340 (-7950 4125);
PAINT GREEN (-7950 4125);
DISPLAY INVISIBLE (-7950 4125);
FORCEPROP 2 LAST CDS_LIB mstr_standard
J 0
(-8275 4250);
DISPLAY 0.723404 (-8275 4250);
PAINT MONO (-8275 4250);
DISPLAY INVISIBLE (-8275 4250);
FORCEADD OFFPAGE..1
(-8275 4200);
FORCEPROP 2 LAST $XR0 45 
J 0
(-8526 4200);
DISPLAY 0.638298 (-8526 4200);
PAINT MONO (-8526 4200);
FORCEPROP 2 LAST PATH I14
J 0
(-8525 4250);
DISPLAY 1.021277 (-8525 4250);
DISPLAY INVISIBLE (-8525 4250);
FORCEPROP 1 LAST COMMENT_BODY TRUE
J 0
(-8150 4100);
DISPLAY 0.872340 (-8150 4100);
PAINT GREEN (-8150 4100);
DISPLAY INVISIBLE (-8150 4100);
FORCEPROP 1 LAST OFFPAGE TRUE
J 0
(-7950 4075);
DISPLAY 0.872340 (-7950 4075);
PAINT GREEN (-7950 4075);
DISPLAY INVISIBLE (-7950 4075);
FORCEPROP 2 LAST CDS_LIB mstr_standard
J 0
(-8275 4200);
DISPLAY 0.808511 (-8275 4200);
DISPLAY INVISIBLE (-8275 4200);
FORCEADD GND..1
(-2125 1825);
FORCEPROP 3 LASTPIN (-2125 1875) SIG_NAME GND\g
J 0
(-2115 1885);
DISPLAY 0.659574 (-2115 1885);
PAINT MONO (-2115 1885);
DISPLAY INVISIBLE (-2115 1885);
FORCEPROP 1 LAST SIZE 1B
J 0
(-2050 1775);
DISPLAY 0.851064 (-2050 1775);
PAINT GREEN (-2050 1775);
DISPLAY INVISIBLE (-2050 1775);
FORCEPROP 2 LAST CDS_LIB mstr_symbols
J 0
(-2125 1825);
DISPLAY 0.723404 (-2125 1825);
DISPLAY INVISIBLE (-2125 1825);
FORCEPROP 1 LAST BODY_TYPE PLUMBING
J 0
(-2170 1782);
DISPLAY 0.340426 (-2170 1782);
PAINT GREEN (-2170 1782);
DISPLAY INVISIBLE (-2170 1782);
FORCEPROP 1 LAST PATH I140
J 0
(-2050 1825);
DISPLAY 0.872340 (-2050 1825);
PAINT AQUA (-2050 1825);
DISPLAY INVISIBLE (-2050 1825);
FORCEPROP 1 LAST VOLTAGE 0.0
J 0
(-2170 1782);
DISPLAY 0.723404 (-2170 1782);
PAINT SKYBLUE (-2170 1782);
DISPLAY INVISIBLE (-2170 1782);
FORCEPROP 1 LAST HDL_POWER GND
J 0
(-2125 1975);
DISPLAY 0.851064 (-2125 1975);
PAINT GREEN (-2125 1975);
DISPLAY INVISIBLE (-2125 1975);
FORCEADD GND..1
(-325 1600);
FORCEPROP 3 LASTPIN (-325 1650) SIG_NAME GND\g
J 0
(-315 1660);
DISPLAY 0.659574 (-315 1660);
PAINT MONO (-315 1660);
DISPLAY INVISIBLE (-315 1660);
FORCEPROP 1 LAST SIZE 1B
J 0
(-250 1550);
DISPLAY 0.851064 (-250 1550);
PAINT GREEN (-250 1550);
DISPLAY INVISIBLE (-250 1550);
FORCEPROP 2 LAST CDS_LIB mstr_symbols
J 0
(-325 1600);
DISPLAY 0.723404 (-325 1600);
DISPLAY INVISIBLE (-325 1600);
FORCEPROP 1 LAST BODY_TYPE PLUMBING
J 0
(-370 1557);
DISPLAY 0.340426 (-370 1557);
PAINT GREEN (-370 1557);
DISPLAY INVISIBLE (-370 1557);
FORCEPROP 1 LAST PATH I141
J 0
(-250 1600);
DISPLAY 0.872340 (-250 1600);
PAINT AQUA (-250 1600);
DISPLAY INVISIBLE (-250 1600);
FORCEPROP 1 LAST VOLTAGE 0.0
J 0
(-370 1557);
DISPLAY 0.723404 (-370 1557);
PAINT SKYBLUE (-370 1557);
DISPLAY INVISIBLE (-370 1557);
FORCEPROP 1 LAST HDL_POWER GND
J 0
(-325 1750);
DISPLAY 0.851064 (-325 1750);
PAINT GREEN (-325 1750);
DISPLAY INVISIBLE (-325 1750);
FORCEADD OFFPAGE..1
(-8275 4100);
FORCEPROP 2 LAST $XR0 45 
J 0
(-8526 4100);
DISPLAY 0.638298 (-8526 4100);
PAINT MONO (-8526 4100);
FORCEPROP 2 LAST PATH I15
J 0
(-8525 4150);
DISPLAY 1.021277 (-8525 4150);
DISPLAY INVISIBLE (-8525 4150);
FORCEPROP 1 LAST COMMENT_BODY TRUE
J 0
(-8150 4000);
DISPLAY 0.872340 (-8150 4000);
PAINT GREEN (-8150 4000);
DISPLAY INVISIBLE (-8150 4000);
FORCEPROP 1 LAST OFFPAGE TRUE
J 0
(-7950 3975);
DISPLAY 0.872340 (-7950 3975);
PAINT GREEN (-7950 3975);
DISPLAY INVISIBLE (-7950 3975);
FORCEPROP 2 LAST CDS_LIB mstr_standard
J 0
(-8275 4100);
DISPLAY 0.723404 (-8275 4100);
PAINT MONO (-8275 4100);
DISPLAY INVISIBLE (-8275 4100);
FORCEADD OFFPAGE..1
(-8275 4350);
FORCEPROP 2 LAST $XR0 45 
J 0
(-8526 4350);
DISPLAY 0.638298 (-8526 4350);
PAINT MONO (-8526 4350);
FORCEPROP 2 LAST PATH I16
J 0
(-8525 4400);
DISPLAY 1.021277 (-8525 4400);
DISPLAY INVISIBLE (-8525 4400);
FORCEPROP 1 LAST COMMENT_BODY TRUE
J 0
(-8150 4250);
DISPLAY 0.872340 (-8150 4250);
PAINT GREEN (-8150 4250);
DISPLAY INVISIBLE (-8150 4250);
FORCEPROP 1 LAST OFFPAGE TRUE
J 0
(-7950 4225);
DISPLAY 0.872340 (-7950 4225);
PAINT GREEN (-7950 4225);
DISPLAY INVISIBLE (-7950 4225);
FORCEPROP 2 LAST CDS_LIB mstr_standard
J 0
(-8275 4350);
DISPLAY 0.808511 (-8275 4350);
DISPLAY INVISIBLE (-8275 4350);
FORCEADD OFFPAGE..1
(-8275 4500);
FORCEPROP 2 LAST $XR0 45 
J 0
(-8526 4500);
DISPLAY 0.638298 (-8526 4500);
PAINT MONO (-8526 4500);
FORCEPROP 2 LAST PATH I17
J 0
(-8525 4550);
DISPLAY 1.021277 (-8525 4550);
DISPLAY INVISIBLE (-8525 4550);
FORCEPROP 1 LAST COMMENT_BODY TRUE
J 0
(-8150 4400);
DISPLAY 0.872340 (-8150 4400);
PAINT GREEN (-8150 4400);
DISPLAY INVISIBLE (-8150 4400);
FORCEPROP 1 LAST OFFPAGE TRUE
J 0
(-7950 4375);
DISPLAY 0.872340 (-7950 4375);
PAINT GREEN (-7950 4375);
DISPLAY INVISIBLE (-7950 4375);
FORCEPROP 2 LAST CDS_LIB mstr_standard
J 0
(-8275 4500);
DISPLAY 0.808511 (-8275 4500);
DISPLAY INVISIBLE (-8275 4500);
FORCEADD SCONN288_DDR506112002KQ..3
(-1225 3600);
FORCEPROP 1 LAST LOCATION J100
J 0
(-1675 5575);
DISPLAY 0.468085 (-1675 5575);
PAINT SKYBLUE (-1675 5575);
FORCEPROP 0 LAST $SEC 3
J 0
(-1675 5725);
DISPLAY 0.680851 (-1675 5725);
PAINT MONO (-1675 5725);
DISPLAY INVISIBLE (-1675 5725);
FORCEPROP 2 LAST CDS_SEC 3
J 0
(-1675 5725);
DISPLAY 1.021277 (-1675 5725);
DISPLAY INVISIBLE (-1675 5725);
FORCEPROP 0 LASTPIN (-625 2000) $PN G1
J 0
(-615 2010);
DISPLAY 0.680851 (-615 2010);
PAINT MONO (-615 2010);
FORCEPROP 0 LASTPIN (-625 1950) $PN G2
J 0
(-615 1960);
DISPLAY 0.680851 (-615 1960);
PAINT MONO (-615 1960);
FORCEPROP 0 LASTPIN (-625 1900) $PN G3
J 0
(-615 1910);
DISPLAY 0.680851 (-615 1910);
PAINT MONO (-615 1910);
FORCEPROP 0 LASTPIN (-1825 5150) $PN 1
J 2
(-1835 5160);
DISPLAY 0.680851 (-1835 5160);
PAINT MONO (-1835 5160);
FORCEPROP 0 LASTPIN (-1825 5200) $PN 145
J 2
(-1835 5210);
DISPLAY 0.680851 (-1835 5210);
PAINT MONO (-1835 5210);
FORCEPROP 0 LASTPIN (-1825 5250) $PN 146
J 2
(-1835 5260);
DISPLAY 0.680851 (-1835 5260);
PAINT MONO (-1835 5260);
FORCEPROP 0 LASTPIN (-625 2100) $PN 6
J 0
(-615 2110);
DISPLAY 0.680851 (-615 2110);
PAINT MONO (-615 2110);
FORCEPROP 0 LASTPIN (-625 2150) $PN 8
J 0
(-615 2160);
DISPLAY 0.680851 (-615 2160);
PAINT MONO (-615 2160);
FORCEPROP 0 LASTPIN (-625 2200) $PN 10
J 0
(-615 2210);
DISPLAY 0.680851 (-615 2210);
PAINT MONO (-615 2210);
FORCEPROP 0 LASTPIN (-625 2250) $PN 13
J 0
(-615 2260);
DISPLAY 0.680851 (-615 2260);
PAINT MONO (-615 2260);
FORCEPROP 0 LASTPIN (-625 2300) $PN 15
J 0
(-615 2310);
DISPLAY 0.680851 (-615 2310);
PAINT MONO (-615 2310);
FORCEPROP 0 LASTPIN (-625 2350) $PN 17
J 0
(-615 2360);
DISPLAY 0.680851 (-615 2360);
PAINT MONO (-615 2360);
FORCEPROP 0 LASTPIN (-625 2400) $PN 19
J 0
(-615 2410);
DISPLAY 0.680851 (-615 2410);
PAINT MONO (-615 2410);
FORCEPROP 0 LASTPIN (-625 2450) $PN 21
J 0
(-615 2460);
DISPLAY 0.680851 (-615 2460);
PAINT MONO (-615 2460);
FORCEPROP 0 LASTPIN (-625 2500) $PN 24
J 0
(-615 2510);
DISPLAY 0.680851 (-615 2510);
PAINT MONO (-615 2510);
FORCEPROP 0 LASTPIN (-625 2550) $PN 26
J 0
(-615 2560);
DISPLAY 0.680851 (-615 2560);
PAINT MONO (-615 2560);
FORCEPROP 0 LASTPIN (-625 2600) $PN 28
J 0
(-615 2610);
DISPLAY 0.680851 (-615 2610);
PAINT MONO (-615 2610);
FORCEPROP 0 LASTPIN (-625 2650) $PN 30
J 0
(-615 2660);
DISPLAY 0.680851 (-615 2660);
PAINT MONO (-615 2660);
FORCEPROP 0 LASTPIN (-625 2700) $PN 32
J 0
(-615 2710);
DISPLAY 0.680851 (-615 2710);
PAINT MONO (-615 2710);
FORCEPROP 0 LASTPIN (-625 2750) $PN 35
J 0
(-615 2760);
DISPLAY 0.680851 (-615 2760);
PAINT MONO (-615 2760);
FORCEPROP 0 LASTPIN (-625 2800) $PN 37
J 0
(-615 2810);
DISPLAY 0.680851 (-615 2810);
PAINT MONO (-615 2810);
FORCEPROP 0 LASTPIN (-625 2850) $PN 39
J 0
(-615 2860);
DISPLAY 0.680851 (-615 2860);
PAINT MONO (-615 2860);
FORCEPROP 0 LASTPIN (-625 2900) $PN 41
J 0
(-615 2910);
DISPLAY 0.680851 (-615 2910);
PAINT MONO (-615 2910);
FORCEPROP 0 LASTPIN (-625 2950) $PN 43
J 0
(-615 2960);
DISPLAY 0.680851 (-615 2960);
PAINT MONO (-615 2960);
FORCEPROP 0 LASTPIN (-625 3000) $PN 46
J 0
(-615 3010);
DISPLAY 0.680851 (-615 3010);
PAINT MONO (-615 3010);
FORCEPROP 0 LASTPIN (-625 3050) $PN 48
J 0
(-615 3060);
DISPLAY 0.680851 (-615 3060);
PAINT MONO (-615 3060);
FORCEPROP 0 LASTPIN (-625 3100) $PN 50
J 0
(-615 3110);
DISPLAY 0.680851 (-615 3110);
PAINT MONO (-615 3110);
FORCEPROP 0 LASTPIN (-625 3150) $PN 52
J 0
(-615 3160);
DISPLAY 0.680851 (-615 3160);
PAINT MONO (-615 3160);
FORCEPROP 0 LASTPIN (-625 3200) $PN 54
J 0
(-615 3210);
DISPLAY 0.680851 (-615 3210);
PAINT MONO (-615 3210);
FORCEPROP 0 LASTPIN (-625 3250) $PN 57
J 0
(-615 3260);
DISPLAY 0.680851 (-615 3260);
PAINT MONO (-615 3260);
FORCEPROP 0 LASTPIN (-625 3300) $PN 59
J 0
(-615 3310);
DISPLAY 0.680851 (-615 3310);
PAINT MONO (-615 3310);
FORCEPROP 0 LASTPIN (-625 3350) $PN 61
J 0
(-615 3360);
DISPLAY 0.680851 (-615 3360);
PAINT MONO (-615 3360);
FORCEPROP 0 LASTPIN (-625 3400) $PN 63
J 0
(-615 3410);
DISPLAY 0.680851 (-615 3410);
PAINT MONO (-615 3410);
FORCEPROP 0 LASTPIN (-625 3450) $PN 65
J 0
(-615 3460);
DISPLAY 0.680851 (-615 3460);
PAINT MONO (-615 3460);
FORCEPROP 0 LASTPIN (-625 3500) $PN 67
J 0
(-615 3510);
DISPLAY 0.680851 (-615 3510);
PAINT MONO (-615 3510);
FORCEPROP 0 LASTPIN (-625 3550) $PN 69
J 0
(-615 3560);
DISPLAY 0.680851 (-615 3560);
PAINT MONO (-615 3560);
FORCEPROP 0 LASTPIN (-625 3600) $PN 71
J 0
(-615 3610);
DISPLAY 0.680851 (-615 3610);
PAINT MONO (-615 3610);
FORCEPROP 0 LASTPIN (-625 3650) $PN 73
J 0
(-615 3660);
DISPLAY 0.680851 (-615 3660);
PAINT MONO (-615 3660);
FORCEPROP 0 LASTPIN (-625 3700) $PN 75
J 0
(-615 3710);
DISPLAY 0.680851 (-615 3710);
PAINT MONO (-615 3710);
FORCEPROP 0 LASTPIN (-625 3750) $PN 77
J 0
(-615 3760);
DISPLAY 0.680851 (-615 3760);
PAINT MONO (-615 3760);
FORCEPROP 0 LASTPIN (-625 3800) $PN 79
J 0
(-615 3810);
DISPLAY 0.680851 (-615 3810);
PAINT MONO (-615 3810);
FORCEPROP 0 LASTPIN (-625 3850) $PN 81
J 0
(-615 3860);
DISPLAY 0.680851 (-615 3860);
PAINT MONO (-615 3860);
FORCEPROP 0 LASTPIN (-625 3900) $PN 83
J 0
(-615 3910);
DISPLAY 0.680851 (-615 3910);
PAINT MONO (-615 3910);
FORCEPROP 0 LASTPIN (-625 3950) $PN 85
J 0
(-615 3960);
DISPLAY 0.680851 (-615 3960);
PAINT MONO (-615 3960);
FORCEPROP 0 LASTPIN (-625 4000) $PN 88
J 0
(-615 4010);
DISPLAY 0.680851 (-615 4010);
PAINT MONO (-615 4010);
FORCEPROP 0 LASTPIN (-625 4050) $PN 90
J 0
(-615 4060);
DISPLAY 0.680851 (-615 4060);
PAINT MONO (-615 4060);
FORCEPROP 0 LASTPIN (-625 4100) $PN 92
J 0
(-615 4110);
DISPLAY 0.680851 (-615 4110);
PAINT MONO (-615 4110);
FORCEPROP 0 LASTPIN (-625 4150) $PN 95
J 0
(-615 4160);
DISPLAY 0.680851 (-615 4160);
PAINT MONO (-615 4160);
FORCEPROP 0 LASTPIN (-625 4200) $PN 97
J 0
(-615 4210);
DISPLAY 0.680851 (-615 4210);
PAINT MONO (-615 4210);
FORCEPROP 0 LASTPIN (-625 4250) $PN 99
J 0
(-615 4260);
DISPLAY 0.680851 (-615 4260);
PAINT MONO (-615 4260);
FORCEPROP 0 LASTPIN (-625 4300) $PN 101
J 0
(-615 4310);
DISPLAY 0.680851 (-615 4310);
PAINT MONO (-615 4310);
FORCEPROP 0 LASTPIN (-625 4350) $PN 103
J 0
(-615 4360);
DISPLAY 0.680851 (-615 4360);
PAINT MONO (-615 4360);
FORCEPROP 0 LASTPIN (-625 4400) $PN 106
J 0
(-615 4410);
DISPLAY 0.680851 (-615 4410);
PAINT MONO (-615 4410);
FORCEPROP 0 LASTPIN (-625 4450) $PN 108
J 0
(-615 4460);
DISPLAY 0.680851 (-615 4460);
PAINT MONO (-615 4460);
FORCEPROP 0 LASTPIN (-625 4500) $PN 110
J 0
(-615 4510);
DISPLAY 0.680851 (-615 4510);
PAINT MONO (-615 4510);
FORCEPROP 0 LASTPIN (-625 4550) $PN 112
J 0
(-615 4560);
DISPLAY 0.680851 (-615 4560);
PAINT MONO (-615 4560);
FORCEPROP 0 LASTPIN (-625 4600) $PN 114
J 0
(-615 4610);
DISPLAY 0.680851 (-615 4610);
PAINT MONO (-615 4610);
FORCEPROP 0 LASTPIN (-625 4650) $PN 117
J 0
(-615 4660);
DISPLAY 0.680851 (-615 4660);
PAINT MONO (-615 4660);
FORCEPROP 0 LASTPIN (-625 4700) $PN 119
J 0
(-615 4710);
DISPLAY 0.680851 (-615 4710);
PAINT MONO (-615 4710);
FORCEPROP 0 LASTPIN (-625 4750) $PN 121
J 0
(-615 4760);
DISPLAY 0.680851 (-615 4760);
PAINT MONO (-615 4760);
FORCEPROP 0 LASTPIN (-625 4800) $PN 123
J 0
(-615 4810);
DISPLAY 0.680851 (-615 4810);
PAINT MONO (-615 4810);
FORCEPROP 0 LASTPIN (-625 4850) $PN 125
J 0
(-615 4860);
DISPLAY 0.680851 (-615 4860);
PAINT MONO (-615 4860);
FORCEPROP 0 LASTPIN (-625 4900) $PN 128
J 0
(-615 4910);
DISPLAY 0.680851 (-615 4910);
PAINT MONO (-615 4910);
FORCEPROP 0 LASTPIN (-625 4950) $PN 130
J 0
(-615 4960);
DISPLAY 0.680851 (-615 4960);
PAINT MONO (-615 4960);
FORCEPROP 0 LASTPIN (-625 5000) $PN 132
J 0
(-615 5010);
DISPLAY 0.680851 (-615 5010);
PAINT MONO (-615 5010);
FORCEPROP 0 LASTPIN (-625 5050) $PN 134
J 0
(-615 5060);
DISPLAY 0.680851 (-615 5060);
PAINT MONO (-615 5060);
FORCEPROP 0 LASTPIN (-625 5100) $PN 136
J 0
(-615 5110);
DISPLAY 0.680851 (-615 5110);
PAINT MONO (-615 5110);
FORCEPROP 0 LASTPIN (-625 5150) $PN 139
J 0
(-615 5160);
DISPLAY 0.680851 (-615 5160);
PAINT MONO (-615 5160);
FORCEPROP 0 LASTPIN (-625 5200) $PN 141
J 0
(-615 5210);
DISPLAY 0.680851 (-615 5210);
PAINT MONO (-615 5210);
FORCEPROP 0 LASTPIN (-625 5250) $PN 143
J 0
(-615 5260);
DISPLAY 0.680851 (-615 5260);
PAINT MONO (-615 5260);
FORCEPROP 0 LASTPIN (-1825 2000) $PN 151
J 2
(-1835 2010);
DISPLAY 0.680851 (-1835 2010);
PAINT MONO (-1835 2010);
FORCEPROP 0 LASTPIN (-1825 2050) $PN 153
J 2
(-1835 2060);
DISPLAY 0.680851 (-1835 2060);
PAINT MONO (-1835 2060);
FORCEPROP 0 LASTPIN (-1825 2100) $PN 155
J 2
(-1835 2110);
DISPLAY 0.680851 (-1835 2110);
PAINT MONO (-1835 2110);
FORCEPROP 0 LASTPIN (-1825 2150) $PN 158
J 2
(-1835 2160);
DISPLAY 0.680851 (-1835 2160);
PAINT MONO (-1835 2160);
FORCEPROP 0 LASTPIN (-1825 2200) $PN 160
J 2
(-1835 2210);
DISPLAY 0.680851 (-1835 2210);
PAINT MONO (-1835 2210);
FORCEPROP 0 LASTPIN (-1825 2250) $PN 162
J 2
(-1835 2260);
DISPLAY 0.680851 (-1835 2260);
PAINT MONO (-1835 2260);
FORCEPROP 0 LASTPIN (-1825 2300) $PN 164
J 2
(-1835 2310);
DISPLAY 0.680851 (-1835 2310);
PAINT MONO (-1835 2310);
FORCEPROP 0 LASTPIN (-1825 2350) $PN 166
J 2
(-1835 2360);
DISPLAY 0.680851 (-1835 2360);
PAINT MONO (-1835 2360);
FORCEPROP 0 LASTPIN (-1825 2400) $PN 169
J 2
(-1835 2410);
DISPLAY 0.680851 (-1835 2410);
PAINT MONO (-1835 2410);
FORCEPROP 0 LASTPIN (-1825 2450) $PN 171
J 2
(-1835 2460);
DISPLAY 0.680851 (-1835 2460);
PAINT MONO (-1835 2460);
FORCEPROP 0 LASTPIN (-1825 2500) $PN 173
J 2
(-1835 2510);
DISPLAY 0.680851 (-1835 2510);
PAINT MONO (-1835 2510);
FORCEPROP 0 LASTPIN (-1825 2550) $PN 175
J 2
(-1835 2560);
DISPLAY 0.680851 (-1835 2560);
PAINT MONO (-1835 2560);
FORCEPROP 0 LASTPIN (-1825 2600) $PN 177
J 2
(-1835 2610);
DISPLAY 0.680851 (-1835 2610);
PAINT MONO (-1835 2610);
FORCEPROP 0 LASTPIN (-1825 2650) $PN 180
J 2
(-1835 2660);
DISPLAY 0.680851 (-1835 2660);
PAINT MONO (-1835 2660);
FORCEPROP 0 LASTPIN (-1825 2700) $PN 182
J 2
(-1835 2710);
DISPLAY 0.680851 (-1835 2710);
PAINT MONO (-1835 2710);
FORCEPROP 0 LASTPIN (-1825 2750) $PN 184
J 2
(-1835 2760);
DISPLAY 0.680851 (-1835 2760);
PAINT MONO (-1835 2760);
FORCEPROP 0 LASTPIN (-1825 2800) $PN 186
J 2
(-1835 2810);
DISPLAY 0.680851 (-1835 2810);
PAINT MONO (-1835 2810);
FORCEPROP 0 LASTPIN (-1825 2850) $PN 188
J 2
(-1835 2860);
DISPLAY 0.680851 (-1835 2860);
PAINT MONO (-1835 2860);
FORCEPROP 0 LASTPIN (-1825 2900) $PN 191
J 2
(-1835 2910);
DISPLAY 0.680851 (-1835 2910);
PAINT MONO (-1835 2910);
FORCEPROP 0 LASTPIN (-1825 2950) $PN 193
J 2
(-1835 2960);
DISPLAY 0.680851 (-1835 2960);
PAINT MONO (-1835 2960);
FORCEPROP 0 LASTPIN (-1825 3000) $PN 195
J 2
(-1835 3010);
DISPLAY 0.680851 (-1835 3010);
PAINT MONO (-1835 3010);
FORCEPROP 0 LASTPIN (-1825 3050) $PN 197
J 2
(-1835 3060);
DISPLAY 0.680851 (-1835 3060);
PAINT MONO (-1835 3060);
FORCEPROP 0 LASTPIN (-1825 3100) $PN 199
J 2
(-1835 3110);
DISPLAY 0.680851 (-1835 3110);
PAINT MONO (-1835 3110);
FORCEPROP 0 LASTPIN (-1825 3150) $PN 202
J 2
(-1835 3160);
DISPLAY 0.680851 (-1835 3160);
PAINT MONO (-1835 3160);
FORCEPROP 0 LASTPIN (-1825 3200) $PN 204
J 2
(-1835 3210);
DISPLAY 0.680851 (-1835 3210);
PAINT MONO (-1835 3210);
FORCEPROP 0 LASTPIN (-1825 3250) $PN 206
J 2
(-1835 3260);
DISPLAY 0.680851 (-1835 3260);
PAINT MONO (-1835 3260);
FORCEPROP 0 LASTPIN (-1825 3300) $PN 208
J 2
(-1835 3310);
DISPLAY 0.680851 (-1835 3310);
PAINT MONO (-1835 3310);
FORCEPROP 0 LASTPIN (-1825 3350) $PN 210
J 2
(-1835 3360);
DISPLAY 0.680851 (-1835 3360);
PAINT MONO (-1835 3360);
FORCEPROP 0 LASTPIN (-1825 3400) $PN 212
J 2
(-1835 3410);
DISPLAY 0.680851 (-1835 3410);
PAINT MONO (-1835 3410);
FORCEPROP 0 LASTPIN (-1825 3450) $PN 214
J 2
(-1835 3460);
DISPLAY 0.680851 (-1835 3460);
PAINT MONO (-1835 3460);
FORCEPROP 0 LASTPIN (-1825 3500) $PN 216
J 2
(-1835 3510);
DISPLAY 0.680851 (-1835 3510);
PAINT MONO (-1835 3510);
FORCEPROP 0 LASTPIN (-1825 3550) $PN 219
J 2
(-1835 3560);
DISPLAY 0.680851 (-1835 3560);
PAINT MONO (-1835 3560);
FORCEPROP 0 LASTPIN (-1825 3600) $PN 222
J 2
(-1835 3610);
DISPLAY 0.680851 (-1835 3610);
PAINT MONO (-1835 3610);
FORCEPROP 0 LASTPIN (-1825 3650) $PN 224
J 2
(-1835 3660);
DISPLAY 0.680851 (-1835 3660);
PAINT MONO (-1835 3660);
FORCEPROP 0 LASTPIN (-1825 3700) $PN 226
J 2
(-1835 3710);
DISPLAY 0.680851 (-1835 3710);
PAINT MONO (-1835 3710);
FORCEPROP 0 LASTPIN (-1825 3750) $PN 228
J 2
(-1835 3760);
DISPLAY 0.680851 (-1835 3760);
PAINT MONO (-1835 3760);
FORCEPROP 0 LASTPIN (-1825 3800) $PN 230
J 2
(-1835 3810);
DISPLAY 0.680851 (-1835 3810);
PAINT MONO (-1835 3810);
FORCEPROP 0 LASTPIN (-1825 3850) $PN 233
J 2
(-1835 3860);
DISPLAY 0.680851 (-1835 3860);
PAINT MONO (-1835 3860);
FORCEPROP 0 LASTPIN (-1825 3900) $PN 235
J 2
(-1835 3910);
DISPLAY 0.680851 (-1835 3910);
PAINT MONO (-1835 3910);
FORCEPROP 0 LASTPIN (-1825 3950) $PN 237
J 2
(-1835 3960);
DISPLAY 0.680851 (-1835 3960);
PAINT MONO (-1835 3960);
FORCEPROP 0 LASTPIN (-1825 4000) $PN 240
J 2
(-1835 4010);
DISPLAY 0.680851 (-1835 4010);
PAINT MONO (-1835 4010);
FORCEPROP 0 LASTPIN (-1825 4050) $PN 242
J 2
(-1835 4060);
DISPLAY 0.680851 (-1835 4060);
PAINT MONO (-1835 4060);
FORCEPROP 0 LASTPIN (-1825 4100) $PN 244
J 2
(-1835 4110);
DISPLAY 0.680851 (-1835 4110);
PAINT MONO (-1835 4110);
FORCEPROP 0 LASTPIN (-1825 4150) $PN 246
J 2
(-1835 4160);
DISPLAY 0.680851 (-1835 4160);
PAINT MONO (-1835 4160);
FORCEPROP 0 LASTPIN (-1825 4200) $PN 248
J 2
(-1835 4210);
DISPLAY 0.680851 (-1835 4210);
PAINT MONO (-1835 4210);
FORCEPROP 0 LASTPIN (-1825 4250) $PN 251
J 2
(-1835 4260);
DISPLAY 0.680851 (-1835 4260);
PAINT MONO (-1835 4260);
FORCEPROP 0 LASTPIN (-1825 4300) $PN 253
J 2
(-1835 4310);
DISPLAY 0.680851 (-1835 4310);
PAINT MONO (-1835 4310);
FORCEPROP 0 LASTPIN (-1825 4350) $PN 255
J 2
(-1835 4360);
DISPLAY 0.680851 (-1835 4360);
PAINT MONO (-1835 4360);
FORCEPROP 0 LASTPIN (-1825 4400) $PN 257
J 2
(-1835 4410);
DISPLAY 0.680851 (-1835 4410);
PAINT MONO (-1835 4410);
FORCEPROP 0 LASTPIN (-1825 4450) $PN 259
J 2
(-1835 4460);
DISPLAY 0.680851 (-1835 4460);
PAINT MONO (-1835 4460);
FORCEPROP 0 LASTPIN (-1825 4500) $PN 262
J 2
(-1835 4510);
DISPLAY 0.680851 (-1835 4510);
PAINT MONO (-1835 4510);
FORCEPROP 0 LASTPIN (-1825 4550) $PN 264
J 2
(-1835 4560);
DISPLAY 0.680851 (-1835 4560);
PAINT MONO (-1835 4560);
FORCEPROP 0 LASTPIN (-1825 4600) $PN 266
J 2
(-1835 4610);
DISPLAY 0.680851 (-1835 4610);
PAINT MONO (-1835 4610);
FORCEPROP 0 LASTPIN (-1825 4650) $PN 268
J 2
(-1835 4660);
DISPLAY 0.680851 (-1835 4660);
PAINT MONO (-1835 4660);
FORCEPROP 0 LASTPIN (-1825 4700) $PN 270
J 2
(-1835 4710);
DISPLAY 0.680851 (-1835 4710);
PAINT MONO (-1835 4710);
FORCEPROP 0 LASTPIN (-1825 4750) $PN 273
J 2
(-1835 4760);
DISPLAY 0.680851 (-1835 4760);
PAINT MONO (-1835 4760);
FORCEPROP 0 LASTPIN (-1825 4800) $PN 275
J 2
(-1835 4810);
DISPLAY 0.680851 (-1835 4810);
PAINT MONO (-1835 4810);
FORCEPROP 0 LASTPIN (-1825 4850) $PN 277
J 2
(-1835 4860);
DISPLAY 0.680851 (-1835 4860);
PAINT MONO (-1835 4860);
FORCEPROP 0 LASTPIN (-1825 4900) $PN 279
J 2
(-1835 4910);
DISPLAY 0.680851 (-1835 4910);
PAINT MONO (-1835 4910);
FORCEPROP 0 LASTPIN (-1825 4950) $PN 281
J 2
(-1835 4960);
DISPLAY 0.680851 (-1835 4960);
PAINT MONO (-1835 4960);
FORCEPROP 0 LASTPIN (-1825 5000) $PN 284
J 2
(-1835 5010);
DISPLAY 0.680851 (-1835 5010);
PAINT MONO (-1835 5010);
FORCEPROP 0 LASTPIN (-1825 5050) $PN 286
J 2
(-1835 5060);
DISPLAY 0.680851 (-1835 5060);
PAINT MONO (-1835 5060);
FORCEPROP 0 LASTPIN (-1825 5100) $PN 288
J 2
(-1835 5110);
DISPLAY 0.680851 (-1835 5110);
PAINT MONO (-1835 5110);
FORCEPROP 2 LAST PART_TYPE SMLF
J 0
(-1675 5675);
DISPLAY 1.021277 (-1675 5675);
FORCEPROP 1 LAST MATERIAL IO
J 0
(-1675 5425);
DISPLAY 0.468085 (-1675 5425);
PAINT SKYBLUE (-1675 5425);
FORCEPROP 1 LAST PART_NUMBER DFHST8FS479
J 0
(-1675 5500);
DISPLAY 0.468085 (-1675 5500);
PAINT SKYBLUE (-1675 5500);
FORCEPROP 2 LAST VALUE SCONN288_DDR506112002KQ
J 0
(-1675 5625);
DISPLAY 0.489362 (-1675 5625);
PAINT SKYBLUE (-1675 5625);
FORCEPROP 1 LAST CDS_LMAN_SYM_OUTLINE -450,1800,450,-1750
J 0
(-1225 3600);
DISPLAY 0.468085 (-1225 3600);
PAINT GREEN (-1225 3600);
DISPLAY INVISIBLE (-1225 3600);
FORCEPROP 1 LAST PATH I176
J 0
(-1225 3600);
DISPLAY 0.723404 (-1225 3600);
PAINT GREEN (-1225 3600);
DISPLAY INVISIBLE (-1225 3600);
FORCEPROP 1 LAST NEEDS_NO_SIZE TRUE
J 0
(-1225 3600);
DISPLAY 0.723404 (-1225 3600);
PAINT GREEN (-1225 3600);
DISPLAY INVISIBLE (-1225 3600);
FORCEPROP 2 LAST CDS_LIB pure_quanta
J 0
(-1225 3600);
DISPLAY INVISIBLE (-1225 3600);
FORCEADD OFFPAGE..6
(-8275 2800);
FORCEPROP 2 LAST $XR5 136 
J 0
(-9185 2800);
DISPLAY 0.638298 (-9185 2800);
PAINT MONO (-9185 2800);
FORCEPROP 2 LAST $XR4 108 
J 0
(-9065 2800);
DISPLAY 0.638298 (-9065 2800);
PAINT MONO (-9065 2800);
FORCEPROP 2 LAST $XR3 107 
J 0
(-8945 2800);
DISPLAY 0.638298 (-8945 2800);
PAINT MONO (-8945 2800);
FORCEPROP 2 LAST $XR2 106 
J 0
(-8825 2800);
DISPLAY 0.638298 (-8825 2800);
PAINT MONO (-8825 2800);
FORCEPROP 2 LAST $XR1 104 
J 0
(-8705 2800);
DISPLAY 0.638298 (-8705 2800);
PAINT MONO (-8705 2800);
FORCEPROP 2 LAST $XR0 103 
J 0
(-8585 2800);
DISPLAY 0.638298 (-8585 2800);
PAINT MONO (-8585 2800);
FORCEPROP 2 LAST PATH I179
J 0
(-8575 2850);
DISPLAY 1.021277 (-8575 2850);
DISPLAY INVISIBLE (-8575 2850);
FORCEPROP 1 LAST COMMENT_BODY TRUE
J 0
(-8175 2725);
DISPLAY 0.872340 (-8175 2725);
PAINT GREEN (-8175 2725);
DISPLAY INVISIBLE (-8175 2725);
FORCEPROP 1 LAST OFFPAGE TRUE
J 0
(-7950 2675);
DISPLAY 0.872340 (-7950 2675);
PAINT GREEN (-7950 2675);
DISPLAY INVISIBLE (-7950 2675);
FORCEPROP 2 LAST CDS_LIB mstr_standard
J 0
(-8275 2800);
DISPLAY 0.808511 (-8275 2800);
DISPLAY INVISIBLE (-8275 2800);
FORCEADD OFFPAGE..1
(-8275 4400);
FORCEPROP 2 LAST $XR0 45 
J 0
(-8526 4400);
DISPLAY 0.638298 (-8526 4400);
PAINT MONO (-8526 4400);
FORCEPROP 2 LAST PATH I18
J 0
(-8525 4450);
DISPLAY 1.021277 (-8525 4450);
DISPLAY INVISIBLE (-8525 4450);
FORCEPROP 1 LAST COMMENT_BODY TRUE
J 0
(-8150 4300);
DISPLAY 0.872340 (-8150 4300);
PAINT GREEN (-8150 4300);
DISPLAY INVISIBLE (-8150 4300);
FORCEPROP 1 LAST OFFPAGE TRUE
J 0
(-7950 4275);
DISPLAY 0.872340 (-7950 4275);
PAINT GREEN (-7950 4275);
DISPLAY INVISIBLE (-7950 4275);
FORCEPROP 2 LAST CDS_LIB mstr_standard
J 0
(-8275 4400);
DISPLAY 0.723404 (-8275 4400);
PAINT MONO (-8275 4400);
DISPLAY INVISIBLE (-8275 4400);
FORCEADD Q_CAP..1
R 2
(-8550 3175);
FORCEPROP 1 LAST LOCATION C168
J 2
(-8600 3275);
DISPLAY 0.489362 (-8600 3275);
PAINT SKYBLUE (-8600 3275);
FORCEPROP 0 LAST $SEC 1
J 0
(-8600 3325);
DISPLAY 0.680851 (-8600 3325);
PAINT MONO (-8600 3325);
DISPLAY INVISIBLE (-8600 3325);
FORCEPROP 0 LAST CDS_SEC 1
J 0
(-8600 3325);
DISPLAY 1.021277 (-8600 3325);
DISPLAY INVISIBLE (-8600 3325);
FORCEPROP 1 LASTPIN (-8550 3275) $PN 1
J 2
(-8560 3255);
DISPLAY 0.489362 (-8560 3255);
PAINT MONO (-8560 3255);
FORCEPROP 1 LASTPIN (-8550 3075) $PN 2
J 2
(-8560 3055);
DISPLAY 0.489362 (-8560 3055);
PAINT MONO (-8560 3055);
FORCEPROP 1 LAST MATERIAL X7R
J 2
(-8600 3075);
DISPLAY 0.489362 (-8600 3075);
PAINT SKYBLUE (-8600 3075);
FORCEPROP 1 LAST TOLERANCE 10%
J 2
(-8600 3125);
DISPLAY 0.489362 (-8600 3125);
PAINT SKYBLUE (-8600 3125);
FORCEPROP 1 LAST VALUE 0.1UF
J 2
(-8600 3225);
DISPLAY 0.489362 (-8600 3225);
PAINT SKYBLUE (-8600 3225);
FORCEPROP 1 LAST PART_NUMBER CH4104K1B00
J 2
(-8600 3025);
DISPLAY 0.489362 (-8600 3025);
PAINT SKYBLUE (-8600 3025);
FORCEPROP 1 LAST VOLTAGE 25V
J 2
(-8600 3175);
DISPLAY 0.489362 (-8600 3175);
PAINT SKYBLUE (-8600 3175);
FORCEPROP 1 LAST PACK_TYPE 0402
J 2
(-8600 2975);
DISPLAY 0.489362 (-8600 2975);
PAINT SKYBLUE (-8600 2975);
FORCEPROP 0 LAST BOM_COST MEM
J 2
(-8605 3320);
DISPLAY 0.595745 (-8605 3320);
PAINT MONO (-8605 3320);
DISPLAY INVISIBLE (-8605 3320);
FORCEPROP 2 LAST CDS_LIB pure_quanta
J 0
(-8550 3175);
DISPLAY INVISIBLE (-8550 3175);
FORCEPROP 1 LAST PATH I185
J 2
(-8600 3325);
DISPLAY 0.978723 (-8600 3325);
PAINT WHITE (-8600 3325);
DISPLAY INVISIBLE (-8600 3325);
FORCEPROP 0 LAST ROOM MEM_CH_A_CPU0_DIMM1
J 2
(-8605 3320);
DISPLAY 0.595745 (-8605 3320);
PAINT RED (-8605 3320);
DISPLAY INVISIBLE (-8605 3320);
FORCEADD GND..1
(-8550 2950);
FORCEPROP 3 LASTPIN (-8550 3000) SIG_NAME GND\g
J 0
(-8540 3010);
DISPLAY 0.659574 (-8540 3010);
PAINT MONO (-8540 3010);
DISPLAY INVISIBLE (-8540 3010);
FORCEPROP 2 LAST BOM_COST MEM
J 0
(-8525 3075);
DISPLAY 0.659574 (-8525 3075);
DISPLAY INVISIBLE (-8525 3075);
FORCEPROP 1 LAST SIZE 1B
J 0
(-8475 2900);
DISPLAY 0.723404 (-8475 2900);
PAINT GREEN (-8475 2900);
DISPLAY INVISIBLE (-8475 2900);
FORCEPROP 2 LAST CDS_LIB mstr_symbols
J 0
(-8550 2950);
DISPLAY 0.808511 (-8550 2950);
DISPLAY INVISIBLE (-8550 2950);
FORCEPROP 1 LAST BODY_TYPE PLUMBING
J 0
(-8595 2907);
DISPLAY 0.276596 (-8595 2907);
PAINT GREEN (-8595 2907);
DISPLAY INVISIBLE (-8595 2907);
FORCEPROP 1 LAST PATH I186
J 0
(-8475 2950);
DISPLAY 0.872340 (-8475 2950);
PAINT AQUA (-8475 2950);
DISPLAY INVISIBLE (-8475 2950);
FORCEPROP 1 LAST VOLTAGE 0
J 0
(-8570 3045);
DISPLAY 0.829787 (-8570 3045);
PAINT SKYBLUE (-8570 3045);
DISPLAY INVISIBLE (-8570 3045);
FORCEPROP 2 LAST ROOM MEM_EFGH_DECOUPLING_CAPS
J 0
(-8525 3025);
DISPLAY 0.659574 (-8525 3025);
PAINT RED (-8525 3025);
DISPLAY INVISIBLE (-8525 3025);
FORCEPROP 1 LAST HDL_POWER GND
J 0
(-8550 3100);
DISPLAY 0.723404 (-8550 3100);
PAINT GREEN (-8550 3100);
DISPLAY INVISIBLE (-8550 3100);
FORCEADD OFFPAGE..6
(-9025 2100);
FORCEPROP 2 LAST $XR5 81 
J 0
(-9305 1992);
DISPLAY 0.638298 (-9305 1992);
PAINT MONO (-9305 1992);
FORCEPROP 2 LAST $XR4 108 
J 0
(-9305 2172);
DISPLAY 0.638298 (-9305 2172);
PAINT MONO (-9305 2172);
FORCEPROP 2 LAST $XR3 107 
J 0
(-9305 2028);
DISPLAY 0.638298 (-9305 2028);
PAINT MONO (-9305 2028);
FORCEPROP 2 LAST $XR2 106 
J 0
(-9305 2136);
DISPLAY 0.638298 (-9305 2136);
PAINT MONO (-9305 2136);
FORCEPROP 2 LAST $XR1 104 
J 0
(-9305 2064);
DISPLAY 0.638298 (-9305 2064);
PAINT MONO (-9305 2064);
FORCEPROP 2 LAST $XR0 103 
J 0
(-9305 2100);
DISPLAY 0.638298 (-9305 2100);
PAINT MONO (-9305 2100);
FORCEPROP 2 LAST PATH I187
J 0
(-8975 2175);
DISPLAY 1.021277 (-8975 2175);
DISPLAY INVISIBLE (-8975 2175);
FORCEPROP 1 LAST COMMENT_BODY TRUE
J 0
(-8925 2025);
DISPLAY 0.872340 (-8925 2025);
PAINT GREEN (-8925 2025);
DISPLAY INVISIBLE (-8925 2025);
FORCEPROP 1 LAST OFFPAGE TRUE
J 0
(-8700 1975);
DISPLAY 0.872340 (-8700 1975);
PAINT GREEN (-8700 1975);
DISPLAY INVISIBLE (-8700 1975);
FORCEPROP 2 LAST CDS_LIB mstr_standard
J 0
(-9025 2100);
DISPLAY INVISIBLE (-9025 2100);
FORCEADD Q_RES..1
R 2
(-8475 2100);
FORCEPROP 1 LAST LOCATION R311
J 2
(-8425 2150);
DISPLAY 0.489362 (-8425 2150);
PAINT SKYBLUE (-8425 2150);
FORCEPROP 0 LAST $SEC 1
J 0
(-8425 2200);
DISPLAY 0.680851 (-8425 2200);
PAINT MONO (-8425 2200);
DISPLAY INVISIBLE (-8425 2200);
FORCEPROP 0 LAST CDS_SEC 1
J 0
(-8425 2200);
DISPLAY 1.021277 (-8425 2200);
DISPLAY INVISIBLE (-8425 2200);
FORCEPROP 1 LASTPIN (-8375 2100) $PN 1
J 2
(-8387 2112);
DISPLAY 0.489362 (-8387 2112);
PAINT MONO (-8387 2112);
FORCEPROP 1 LASTPIN (-8575 2100) $PN 2
J 2
(-8537 2112);
DISPLAY 0.489362 (-8537 2112);
PAINT MONO (-8537 2112);
FORCEPROP 1 LAST VALUE 0
J 0
(-8475 2050);
DISPLAY 0.489362 (-8475 2050);
PAINT SKYBLUE (-8475 2050);
FORCEPROP 2 LAST CDS_LIB pure_quanta
J 0
(-8475 2100);
DISPLAY INVISIBLE (-8475 2100);
FORCEPROP 2 LAST BOM_COST MEM
J 0
(-8500 2250);
DISPLAY 0.744681 (-8500 2250);
PAINT WHITE (-8500 2250);
DISPLAY INVISIBLE (-8500 2250);
FORCEPROP 1 LAST PATH I188
J 2
(-8425 2250);
DISPLAY 0.978723 (-8425 2250);
PAINT WHITE (-8425 2250);
DISPLAY INVISIBLE (-8425 2250);
FORCEPROP 1 LAST WATTAGE 1/16W
J 0
(-8400 2025);
DISPLAY 0.489362 (-8400 2025);
PAINT SKYBLUE (-8400 2025);
DISPLAY INVISIBLE (-8400 2025);
FORCEPROP 1 LAST MATERIAL CHIP
J 0
(-8650 2075);
DISPLAY 0.489362 (-8650 2075);
PAINT SKYBLUE (-8650 2075);
DISPLAY INVISIBLE (-8650 2075);
FORCEPROP 1 LAST TOLERANCE 5%
J 2
(-8350 2075);
DISPLAY 0.489362 (-8350 2075);
PAINT SKYBLUE (-8350 2075);
DISPLAY INVISIBLE (-8350 2075);
FORCEPROP 1 LAST PART_NUMBER CS00002JB38
J 0
(-8575 2150);
DISPLAY 0.489362 (-8575 2150);
PAINT SKYBLUE (-8575 2150);
DISPLAY INVISIBLE (-8575 2150);
FORCEPROP 1 LAST PACK_TYPE 0402LF
J 0
(-8650 2025);
DISPLAY 0.489362 (-8650 2025);
PAINT SKYBLUE (-8650 2025);
DISPLAY INVISIBLE (-8650 2025);
FORCEPROP 2 LAST ROOM RST_CPU0_PLD_TO_DIMM
J 0
(-8500 2200);
DISPLAY 0.744681 (-8500 2200);
PAINT RED (-8500 2200);
DISPLAY INVISIBLE (-8500 2200);
FORCEADD VCC_CORE..1
(-8350 2425);
FORCEPROP 3 LASTPIN (-8350 2375) SIG_NAME P3V3_STBY\g
J 0
(-8340 2385);
DISPLAY 0.659574 (-8340 2385);
PAINT MONO (-8340 2385);
DISPLAY INVISIBLE (-8340 2385);
FORCEPROP 1 LAST HDL_POWER P3V3_STBY
J 1
(-8350 2475);
DISPLAY 0.489362 (-8350 2475);
PAINT GREEN (-8350 2475);
FORCEPROP 2 LAST CDS_LIB mstr_symbols
J 0
(-8350 2425);
DISPLAY INVISIBLE (-8350 2425);
FORCEPROP 1 LAST PATH I189
J 0
(-8300 2450);
DISPLAY 0.872340 (-8300 2450);
PAINT AQUA (-8300 2450);
DISPLAY INVISIBLE (-8300 2450);
FORCEPROP 0 LAST VOLTAGE 3.3
J 0
(-8625 2575);
DISPLAY 1.021277 (-8625 2575);
PAINT SKYBLUE (-8625 2575);
DISPLAY INVISIBLE (-8625 2575);
FORCEPROP 2 LAST ROOM PVCCINFAON_CPU0_CTRL
J 0
(-8350 2525);
DISPLAY 0.808511 (-8350 2525);
PAINT RED (-8350 2525);
DISPLAY INVISIBLE (-8350 2525);
FORCEADD OFFPAGE..1
(-8275 4550);
FORCEPROP 2 LAST $XR0 45 
J 0
(-8526 4550);
DISPLAY 0.638298 (-8526 4550);
PAINT MONO (-8526 4550);
FORCEPROP 2 LAST PATH I19
J 0
(-8525 4600);
DISPLAY 1.021277 (-8525 4600);
DISPLAY INVISIBLE (-8525 4600);
FORCEPROP 1 LAST COMMENT_BODY TRUE
J 0
(-8150 4450);
DISPLAY 0.872340 (-8150 4450);
PAINT GREEN (-8150 4450);
DISPLAY INVISIBLE (-8150 4450);
FORCEPROP 1 LAST OFFPAGE TRUE
J 0
(-7950 4425);
DISPLAY 0.872340 (-7950 4425);
PAINT GREEN (-7950 4425);
DISPLAY INVISIBLE (-7950 4425);
FORCEPROP 2 LAST CDS_LIB mstr_standard
J 0
(-8275 4550);
DISPLAY 0.723404 (-8275 4550);
PAINT MONO (-8275 4550);
DISPLAY INVISIBLE (-8275 4550);
FORCEADD Q_RES..2
(-8350 2250);
FORCEPROP 1 LAST LOCATION R112
J 0
(-8305 2375);
DISPLAY 0.489362 (-8305 2375);
PAINT SKYBLUE (-8305 2375);
FORCEPROP 0 LAST $SEC 1
J 0
(-8300 2425);
DISPLAY 0.680851 (-8300 2425);
PAINT MONO (-8300 2425);
DISPLAY INVISIBLE (-8300 2425);
FORCEPROP 0 LAST CDS_SEC 1
J 0
(-8300 2425);
DISPLAY 1.021277 (-8300 2425);
DISPLAY INVISIBLE (-8300 2425);
FORCEPROP 1 LASTPIN (-8350 2350) $PN 1
J 0
(-8345 2312);
DISPLAY 0.489362 (-8345 2312);
PAINT MONO (-8345 2312);
FORCEPROP 1 LASTPIN (-8350 2150) $PN 2
J 0
(-8345 2160);
DISPLAY 0.489362 (-8345 2160);
PAINT MONO (-8345 2160);
FORCEPROP 1 LAST WATTAGE 1/16W
J 0
(-8300 2275);
DISPLAY 0.489362 (-8300 2275);
PAINT SKYBLUE (-8300 2275);
FORCEPROP 1 LAST MATERIAL EMPTY
J 0
(-8300 2250);
DISPLAY 0.489362 (-8300 2250);
PAINT RED (-8300 2250);
FORCEPROP 1 LAST TOLERANCE 5%
J 0
(-8300 2300);
DISPLAY 0.489362 (-8300 2300);
PAINT SKYBLUE (-8300 2300);
FORCEPROP 1 LAST VALUE 1K
J 0
(-8305 2325);
DISPLAY 0.489362 (-8305 2325);
PAINT SKYBLUE (-8305 2325);
FORCEPROP 1 LAST PACK_TYPE 0402LF
J 0
(-8300 2200);
DISPLAY 0.489362 (-8300 2200);
PAINT SKYBLUE (-8300 2200);
FORCEPROP 2 LAST CDS_LIB pure_quanta
J 0
(-8350 2250);
DISPLAY INVISIBLE (-8350 2250);
FORCEPROP 2 LAST BOM_COST MEM
J 0
(-8300 2425);
DISPLAY 0.808511 (-8300 2425);
DISPLAY INVISIBLE (-8300 2425);
FORCEPROP 1 LAST PATH I190
J 0
(-8300 2425);
DISPLAY 0.978723 (-8300 2425);
PAINT WHITE (-8300 2425);
DISPLAY INVISIBLE (-8300 2425);
FORCEPROP 1 LAST PART_NUMBER TMP_QCS21002JB34
J 0
(-8300 2225);
DISPLAY 0.489362 (-8300 2225);
PAINT SKYBLUE (-8300 2225);
DISPLAY INVISIBLE (-8300 2225);
FORCEPROP 2 LAST ROOM MEM_CH_A_CPU0_DIMM1
J 0
(-8300 2475);
DISPLAY 0.808511 (-8300 2475);
PAINT RED (-8300 2475);
DISPLAY INVISIBLE (-8300 2475);
FORCEADD TAP..1
(-3250 3100);
FORCEPROP 3 LASTPIN (-3300 3100) SIG_NAME M_I_CPU1_SB_DQS_DN<7>
J 0
(-3290 3110);
DISPLAY 0.659574 (-3290 3110);
PAINT MONO (-3290 3110);
DISPLAY INVISIBLE (-3290 3110);
FORCEPROP 1 LASTPIN (-3300 3100) BN 7
J 0
(-3312 3108);
DISPLAY 0.489362 (-3312 3108);
PAINT GREEN (-3312 3108);
FORCEPROP 2 LAST CDS_LIB mstr_standard
J 0
(-3250 3100);
DISPLAY 0.723404 (-3250 3100);
PAINT MONO (-3250 3100);
DISPLAY INVISIBLE (-3250 3100);
FORCEPROP 1 LAST BODY_TYPE PLUMBING
J 0
(-3250 3150);
DISPLAY 0.872340 (-3250 3150);
PAINT GREEN (-3250 3150);
DISPLAY INVISIBLE (-3250 3150);
FORCEPROP 1 LAST HDL_TAP TRUE
J 0
(-2925 2975);
DISPLAY 0.872340 (-2925 2975);
DISPLAY INVISIBLE (-2925 2975);
FORCEPROP 1 LAST PATH I191
J 0
(-3252 3100);
DISPLAY 0.872340 (-3252 3100);
PAINT GREEN (-3252 3100);
DISPLAY INVISIBLE (-3252 3100);
FORCEADD TAP..1
(-3250 3300);
FORCEPROP 3 LASTPIN (-3300 3300) SIG_NAME M_I_CPU1_SB_DQS_DN<9>
J 0
(-3290 3310);
DISPLAY 0.659574 (-3290 3310);
PAINT MONO (-3290 3310);
DISPLAY INVISIBLE (-3290 3310);
FORCEPROP 1 LASTPIN (-3300 3300) BN 9
J 0
(-3312 3308);
DISPLAY 0.489362 (-3312 3308);
PAINT GREEN (-3312 3308);
FORCEPROP 2 LAST CDS_LIB mstr_standard
J 0
(-3250 3300);
DISPLAY 0.723404 (-3250 3300);
PAINT MONO (-3250 3300);
DISPLAY INVISIBLE (-3250 3300);
FORCEPROP 1 LAST BODY_TYPE PLUMBING
J 0
(-3250 3350);
DISPLAY 0.872340 (-3250 3350);
PAINT GREEN (-3250 3350);
DISPLAY INVISIBLE (-3250 3350);
FORCEPROP 1 LAST HDL_TAP TRUE
J 0
(-2925 3175);
DISPLAY 0.872340 (-2925 3175);
DISPLAY INVISIBLE (-2925 3175);
FORCEPROP 1 LAST PATH I192
J 0
(-3252 3300);
DISPLAY 0.872340 (-3252 3300);
PAINT GREEN (-3252 3300);
DISPLAY INVISIBLE (-3252 3300);
FORCEADD TAP..1
(-3250 3450);
FORCEPROP 3 LASTPIN (-3300 3450) SIG_NAME M_I_CPU1_SA_DQS_DN<0>
J 0
(-3290 3460);
DISPLAY 0.659574 (-3290 3460);
PAINT MONO (-3290 3460);
DISPLAY INVISIBLE (-3290 3460);
FORCEPROP 1 LASTPIN (-3300 3450) BN 0
J 0
(-3312 3458);
DISPLAY 0.489362 (-3312 3458);
PAINT GREEN (-3312 3458);
FORCEPROP 2 LAST CDS_LIB mstr_standard
J 0
(-3250 3450);
DISPLAY 0.723404 (-3250 3450);
PAINT MONO (-3250 3450);
DISPLAY INVISIBLE (-3250 3450);
FORCEPROP 1 LAST BODY_TYPE PLUMBING
J 0
(-3250 3500);
DISPLAY 0.872340 (-3250 3500);
PAINT GREEN (-3250 3500);
DISPLAY INVISIBLE (-3250 3500);
FORCEPROP 1 LAST HDL_TAP TRUE
J 0
(-2925 3325);
DISPLAY 0.872340 (-2925 3325);
DISPLAY INVISIBLE (-2925 3325);
FORCEPROP 1 LAST PATH I193
J 0
(-3252 3450);
DISPLAY 0.872340 (-3252 3450);
PAINT GREEN (-3252 3450);
DISPLAY INVISIBLE (-3252 3450);
FORCEADD TAP..1
(-3250 3550);
FORCEPROP 3 LASTPIN (-3300 3550) SIG_NAME M_I_CPU1_SA_DQS_DN<1>
J 0
(-3290 3560);
DISPLAY 0.659574 (-3290 3560);
PAINT MONO (-3290 3560);
DISPLAY INVISIBLE (-3290 3560);
FORCEPROP 1 LASTPIN (-3300 3550) BN 1
J 0
(-3312 3558);
DISPLAY 0.489362 (-3312 3558);
PAINT GREEN (-3312 3558);
FORCEPROP 2 LAST CDS_LIB mstr_standard
J 0
(-3250 3550);
DISPLAY 0.723404 (-3250 3550);
PAINT MONO (-3250 3550);
DISPLAY INVISIBLE (-3250 3550);
FORCEPROP 1 LAST BODY_TYPE PLUMBING
J 0
(-3250 3600);
DISPLAY 0.872340 (-3250 3600);
PAINT GREEN (-3250 3600);
DISPLAY INVISIBLE (-3250 3600);
FORCEPROP 1 LAST HDL_TAP TRUE
J 0
(-2925 3425);
DISPLAY 0.872340 (-2925 3425);
DISPLAY INVISIBLE (-2925 3425);
FORCEPROP 1 LAST PATH I194
J 0
(-3252 3550);
DISPLAY 0.872340 (-3252 3550);
PAINT GREEN (-3252 3550);
DISPLAY INVISIBLE (-3252 3550);
FORCEADD TAP..1
(-3450 3800);
FORCEPROP 3 LASTPIN (-3500 3800) SIG_NAME M_I_CPU1_SA_DQS_DP<3>
J 0
(-3490 3810);
DISPLAY 0.659574 (-3490 3810);
PAINT MONO (-3490 3810);
DISPLAY INVISIBLE (-3490 3810);
FORCEPROP 1 LASTPIN (-3500 3800) BN 3
J 0
(-3512 3808);
DISPLAY 0.489362 (-3512 3808);
PAINT GREEN (-3512 3808);
FORCEPROP 2 LAST CDS_LIB mstr_standard
J 0
(-3450 3800);
DISPLAY 0.723404 (-3450 3800);
PAINT MONO (-3450 3800);
DISPLAY INVISIBLE (-3450 3800);
FORCEPROP 1 LAST BODY_TYPE PLUMBING
J 0
(-3450 3850);
DISPLAY 0.872340 (-3450 3850);
PAINT GREEN (-3450 3850);
DISPLAY INVISIBLE (-3450 3850);
FORCEPROP 1 LAST HDL_TAP TRUE
J 0
(-3125 3675);
DISPLAY 0.872340 (-3125 3675);
DISPLAY INVISIBLE (-3125 3675);
FORCEPROP 1 LAST PATH I195
J 0
(-3452 3800);
DISPLAY 0.872340 (-3452 3800);
PAINT GREEN (-3452 3800);
DISPLAY INVISIBLE (-3452 3800);
FORCEADD OFFPAGE..2
(-2450 4450);
FORCEPROP 2 LAST $XR0 45 
J 0
(-2261 4450);
DISPLAY 0.638298 (-2261 4450);
PAINT MONO (-2261 4450);
FORCEPROP 1 LAST COMMENT_BODY TRUE
J 0
(-2495 4355);
DISPLAY 0.872340 (-2495 4355);
PAINT GREEN (-2495 4355);
DISPLAY INVISIBLE (-2495 4355);
FORCEPROP 1 LAST OFFPAGE TRUE
J 0
(-2125 4325);
DISPLAY 0.723404 (-2125 4325);
PAINT GREEN (-2125 4325);
DISPLAY INVISIBLE (-2125 4325);
FORCEPROP 2 LAST CDS_LIB mstr_standard
J 0
(-2450 4450);
DISPLAY 0.723404 (-2450 4450);
PAINT MONO (-2450 4450);
DISPLAY INVISIBLE (-2450 4450);
FORCEPROP 2 LAST PATH I197
J 0
(-2250 4500);
DISPLAY 0.680851 (-2250 4500);
DISPLAY INVISIBLE (-2250 4500);
FORCEADD OFFPAGE..2
(-2450 4400);
FORCEPROP 2 LAST $XR0 45 
J 0
(-2261 4400);
DISPLAY 0.638298 (-2261 4400);
PAINT MONO (-2261 4400);
FORCEPROP 1 LAST COMMENT_BODY TRUE
J 0
(-2495 4305);
DISPLAY 0.872340 (-2495 4305);
PAINT GREEN (-2495 4305);
DISPLAY INVISIBLE (-2495 4305);
FORCEPROP 1 LAST OFFPAGE TRUE
J 0
(-2125 4275);
DISPLAY 0.723404 (-2125 4275);
PAINT GREEN (-2125 4275);
DISPLAY INVISIBLE (-2125 4275);
FORCEPROP 2 LAST CDS_LIB mstr_standard
J 0
(-2450 4400);
DISPLAY 0.723404 (-2450 4400);
PAINT MONO (-2450 4400);
DISPLAY INVISIBLE (-2450 4400);
FORCEPROP 2 LAST PATH I198
J 0
(-2250 4450);
DISPLAY 0.680851 (-2250 4450);
DISPLAY INVISIBLE (-2250 4450);
FORCEADD OFFPAGE..2
(-2450 3400);
FORCEPROP 2 LAST $XR0 45 
J 0
(-2261 3400);
DISPLAY 0.638298 (-2261 3400);
PAINT MONO (-2261 3400);
FORCEPROP 1 LAST COMMENT_BODY TRUE
J 0
(-2495 3305);
DISPLAY 0.872340 (-2495 3305);
PAINT GREEN (-2495 3305);
DISPLAY INVISIBLE (-2495 3305);
FORCEPROP 1 LAST OFFPAGE TRUE
J 0
(-2125 3275);
DISPLAY 0.723404 (-2125 3275);
PAINT GREEN (-2125 3275);
DISPLAY INVISIBLE (-2125 3275);
FORCEPROP 2 LAST CDS_LIB mstr_standard
J 0
(-2450 3400);
DISPLAY 0.723404 (-2450 3400);
PAINT MONO (-2450 3400);
DISPLAY INVISIBLE (-2450 3400);
FORCEPROP 2 LAST PATH I199
J 0
(-2250 3450);
DISPLAY 0.680851 (-2250 3450);
DISPLAY INVISIBLE (-2250 3450);
FORCEADD OFFPAGE..5
(-8275 1950);
FORCEPROP 2 LAST $XR0 45 
J 0
(-8529 1950);
DISPLAY 0.638298 (-8529 1950);
PAINT MONO (-8529 1950);
FORCEPROP 2 LAST PATH I2
J 0
(-8475 2000);
DISPLAY 1.021277 (-8475 2000);
DISPLAY INVISIBLE (-8475 2000);
FORCEPROP 1 LAST COMMENT_BODY TRUE
J 0
(-8175 1875);
DISPLAY 0.872340 (-8175 1875);
PAINT GREEN (-8175 1875);
DISPLAY INVISIBLE (-8175 1875);
FORCEPROP 1 LAST OFFPAGE TRUE
J 0
(-7950 1825);
DISPLAY 0.872340 (-7950 1825);
PAINT GREEN (-7950 1825);
DISPLAY INVISIBLE (-7950 1825);
FORCEPROP 2 LAST CDS_LIB mstr_standard
J 0
(-8275 1950);
DISPLAY 0.808511 (-8275 1950);
DISPLAY INVISIBLE (-8275 1950);
FORCEADD OFFPAGE..1
(-8275 5400);
FORCEPROP 2 LAST $XR0 45 
J 0
(-8526 5400);
DISPLAY 0.638298 (-8526 5400);
PAINT MONO (-8526 5400);
FORCEPROP 2 LAST PATH I20
J 0
(-8525 5450);
DISPLAY 1.021277 (-8525 5450);
DISPLAY INVISIBLE (-8525 5450);
FORCEPROP 1 LAST COMMENT_BODY TRUE
J 0
(-8150 5300);
DISPLAY 0.872340 (-8150 5300);
PAINT GREEN (-8150 5300);
DISPLAY INVISIBLE (-8150 5300);
FORCEPROP 1 LAST OFFPAGE TRUE
J 0
(-7950 5275);
DISPLAY 0.872340 (-7950 5275);
PAINT GREEN (-7950 5275);
DISPLAY INVISIBLE (-7950 5275);
FORCEPROP 2 LAST CDS_LIB mstr_standard
J 0
(-8275 5400);
DISPLAY 0.723404 (-8275 5400);
PAINT MONO (-8275 5400);
DISPLAY INVISIBLE (-8275 5400);
FORCEADD OFFPAGE..2
(-2450 3350);
FORCEPROP 2 LAST $XR0 45 
J 0
(-2261 3350);
DISPLAY 0.638298 (-2261 3350);
PAINT MONO (-2261 3350);
FORCEPROP 1 LAST COMMENT_BODY TRUE
J 0
(-2495 3255);
DISPLAY 0.872340 (-2495 3255);
PAINT GREEN (-2495 3255);
DISPLAY INVISIBLE (-2495 3255);
FORCEPROP 1 LAST OFFPAGE TRUE
J 0
(-2125 3225);
DISPLAY 0.723404 (-2125 3225);
PAINT GREEN (-2125 3225);
DISPLAY INVISIBLE (-2125 3225);
FORCEPROP 2 LAST CDS_LIB mstr_standard
J 0
(-2450 3350);
DISPLAY 0.723404 (-2450 3350);
PAINT MONO (-2450 3350);
DISPLAY INVISIBLE (-2450 3350);
FORCEPROP 2 LAST PATH I200
J 0
(-2250 3400);
DISPLAY 0.680851 (-2250 3400);
DISPLAY INVISIBLE (-2250 3400);
FORCEADD TAP..1
(-3250 4350);
FORCEPROP 3 LASTPIN (-3300 4350) SIG_NAME M_I_CPU1_SA_DQS_DN<9>
J 0
(-3290 4360);
DISPLAY 0.659574 (-3290 4360);
PAINT MONO (-3290 4360);
DISPLAY INVISIBLE (-3290 4360);
FORCEPROP 1 LASTPIN (-3300 4350) BN 9
J 0
(-3312 4358);
DISPLAY 0.489362 (-3312 4358);
PAINT GREEN (-3312 4358);
FORCEPROP 2 LAST CDS_LIB mstr_standard
J 0
(-3250 4350);
DISPLAY 0.723404 (-3250 4350);
PAINT MONO (-3250 4350);
DISPLAY INVISIBLE (-3250 4350);
FORCEPROP 1 LAST BODY_TYPE PLUMBING
J 0
(-3250 4400);
DISPLAY 0.872340 (-3250 4400);
PAINT GREEN (-3250 4400);
DISPLAY INVISIBLE (-3250 4400);
FORCEPROP 1 LAST HDL_TAP TRUE
J 0
(-2925 4225);
DISPLAY 0.872340 (-2925 4225);
DISPLAY INVISIBLE (-2925 4225);
FORCEPROP 1 LAST PATH I201
J 0
(-3252 4350);
DISPLAY 0.872340 (-3252 4350);
PAINT GREEN (-3252 4350);
DISPLAY INVISIBLE (-3252 4350);
FORCEADD TAP..1
(-3450 4400);
FORCEPROP 3 LASTPIN (-3500 4400) SIG_NAME M_I_CPU1_SA_DQS_DP<9>
J 0
(-3490 4410);
DISPLAY 0.659574 (-3490 4410);
PAINT MONO (-3490 4410);
DISPLAY INVISIBLE (-3490 4410);
FORCEPROP 1 LASTPIN (-3500 4400) BN 9
J 0
(-3512 4408);
DISPLAY 0.489362 (-3512 4408);
PAINT GREEN (-3512 4408);
FORCEPROP 2 LAST CDS_LIB mstr_standard
J 0
(-3450 4400);
DISPLAY 0.723404 (-3450 4400);
PAINT MONO (-3450 4400);
DISPLAY INVISIBLE (-3450 4400);
FORCEPROP 1 LAST BODY_TYPE PLUMBING
J 0
(-3450 4450);
DISPLAY 0.872340 (-3450 4450);
PAINT GREEN (-3450 4450);
DISPLAY INVISIBLE (-3450 4450);
FORCEPROP 1 LAST HDL_TAP TRUE
J 0
(-3125 4275);
DISPLAY 0.872340 (-3125 4275);
DISPLAY INVISIBLE (-3125 4275);
FORCEPROP 1 LAST PATH I202
J 0
(-3452 4400);
DISPLAY 0.872340 (-3452 4400);
PAINT GREEN (-3452 4400);
DISPLAY INVISIBLE (-3452 4400);
FORCEADD TAP..1
(-3450 4300);
FORCEPROP 3 LASTPIN (-3500 4300) SIG_NAME M_I_CPU1_SA_DQS_DP<8>
J 0
(-3490 4310);
DISPLAY 0.659574 (-3490 4310);
PAINT MONO (-3490 4310);
DISPLAY INVISIBLE (-3490 4310);
FORCEPROP 1 LASTPIN (-3500 4300) BN 8
J 0
(-3512 4308);
DISPLAY 0.489362 (-3512 4308);
PAINT GREEN (-3512 4308);
FORCEPROP 2 LAST CDS_LIB mstr_standard
J 0
(-3450 4300);
DISPLAY 0.723404 (-3450 4300);
PAINT MONO (-3450 4300);
DISPLAY INVISIBLE (-3450 4300);
FORCEPROP 1 LAST BODY_TYPE PLUMBING
J 0
(-3450 4350);
DISPLAY 0.872340 (-3450 4350);
PAINT GREEN (-3450 4350);
DISPLAY INVISIBLE (-3450 4350);
FORCEPROP 1 LAST HDL_TAP TRUE
J 0
(-3125 4175);
DISPLAY 0.872340 (-3125 4175);
DISPLAY INVISIBLE (-3125 4175);
FORCEPROP 1 LAST PATH I203
J 0
(-3452 4300);
DISPLAY 0.872340 (-3452 4300);
PAINT GREEN (-3452 4300);
DISPLAY INVISIBLE (-3452 4300);
FORCEADD TAP..1
(-3250 4250);
FORCEPROP 3 LASTPIN (-3300 4250) SIG_NAME M_I_CPU1_SA_DQS_DN<8>
J 0
(-3290 4260);
DISPLAY 0.659574 (-3290 4260);
PAINT MONO (-3290 4260);
DISPLAY INVISIBLE (-3290 4260);
FORCEPROP 1 LASTPIN (-3300 4250) BN 8
J 0
(-3312 4258);
DISPLAY 0.489362 (-3312 4258);
PAINT GREEN (-3312 4258);
FORCEPROP 2 LAST CDS_LIB mstr_standard
J 0
(-3250 4250);
DISPLAY 0.723404 (-3250 4250);
PAINT MONO (-3250 4250);
DISPLAY INVISIBLE (-3250 4250);
FORCEPROP 1 LAST BODY_TYPE PLUMBING
J 0
(-3250 4300);
DISPLAY 0.872340 (-3250 4300);
PAINT GREEN (-3250 4300);
DISPLAY INVISIBLE (-3250 4300);
FORCEPROP 1 LAST HDL_TAP TRUE
J 0
(-2925 4125);
DISPLAY 0.872340 (-2925 4125);
DISPLAY INVISIBLE (-2925 4125);
FORCEPROP 1 LAST PATH I204
J 0
(-3252 4250);
DISPLAY 0.872340 (-3252 4250);
PAINT GREEN (-3252 4250);
DISPLAY INVISIBLE (-3252 4250);
FORCEADD TAP..1
(-3250 4150);
FORCEPROP 3 LASTPIN (-3300 4150) SIG_NAME M_I_CPU1_SA_DQS_DN<7>
J 0
(-3290 4160);
DISPLAY 0.659574 (-3290 4160);
PAINT MONO (-3290 4160);
DISPLAY INVISIBLE (-3290 4160);
FORCEPROP 1 LASTPIN (-3300 4150) BN 7
J 0
(-3312 4158);
DISPLAY 0.489362 (-3312 4158);
PAINT GREEN (-3312 4158);
FORCEPROP 2 LAST CDS_LIB mstr_standard
J 0
(-3250 4150);
DISPLAY 0.723404 (-3250 4150);
PAINT MONO (-3250 4150);
DISPLAY INVISIBLE (-3250 4150);
FORCEPROP 1 LAST BODY_TYPE PLUMBING
J 0
(-3250 4200);
DISPLAY 0.872340 (-3250 4200);
PAINT GREEN (-3250 4200);
DISPLAY INVISIBLE (-3250 4200);
FORCEPROP 1 LAST HDL_TAP TRUE
J 0
(-2925 4025);
DISPLAY 0.872340 (-2925 4025);
DISPLAY INVISIBLE (-2925 4025);
FORCEPROP 1 LAST PATH I205
J 0
(-3252 4150);
DISPLAY 0.872340 (-3252 4150);
PAINT GREEN (-3252 4150);
DISPLAY INVISIBLE (-3252 4150);
FORCEADD TAP..1
(-3250 4050);
FORCEPROP 3 LASTPIN (-3300 4050) SIG_NAME M_I_CPU1_SA_DQS_DN<6>
J 0
(-3290 4060);
DISPLAY 0.659574 (-3290 4060);
PAINT MONO (-3290 4060);
DISPLAY INVISIBLE (-3290 4060);
FORCEPROP 1 LASTPIN (-3300 4050) BN 6
J 0
(-3312 4058);
DISPLAY 0.489362 (-3312 4058);
PAINT GREEN (-3312 4058);
FORCEPROP 2 LAST CDS_LIB mstr_standard
J 0
(-3250 4050);
DISPLAY 0.723404 (-3250 4050);
PAINT MONO (-3250 4050);
DISPLAY INVISIBLE (-3250 4050);
FORCEPROP 1 LAST BODY_TYPE PLUMBING
J 0
(-3250 4100);
DISPLAY 0.872340 (-3250 4100);
PAINT GREEN (-3250 4100);
DISPLAY INVISIBLE (-3250 4100);
FORCEPROP 1 LAST HDL_TAP TRUE
J 0
(-2925 3925);
DISPLAY 0.872340 (-2925 3925);
DISPLAY INVISIBLE (-2925 3925);
FORCEPROP 1 LAST PATH I206
J 0
(-3252 4050);
DISPLAY 0.872340 (-3252 4050);
PAINT GREEN (-3252 4050);
DISPLAY INVISIBLE (-3252 4050);
FORCEADD TAP..1
(-3250 3950);
FORCEPROP 3 LASTPIN (-3300 3950) SIG_NAME M_I_CPU1_SA_DQS_DN<5>
J 0
(-3290 3960);
DISPLAY 0.659574 (-3290 3960);
PAINT MONO (-3290 3960);
DISPLAY INVISIBLE (-3290 3960);
FORCEPROP 1 LASTPIN (-3300 3950) BN 5
J 0
(-3312 3958);
DISPLAY 0.489362 (-3312 3958);
PAINT GREEN (-3312 3958);
FORCEPROP 2 LAST CDS_LIB mstr_standard
J 0
(-3250 3950);
DISPLAY 0.723404 (-3250 3950);
PAINT MONO (-3250 3950);
DISPLAY INVISIBLE (-3250 3950);
FORCEPROP 1 LAST BODY_TYPE PLUMBING
J 0
(-3250 4000);
DISPLAY 0.872340 (-3250 4000);
PAINT GREEN (-3250 4000);
DISPLAY INVISIBLE (-3250 4000);
FORCEPROP 1 LAST HDL_TAP TRUE
J 0
(-2925 3825);
DISPLAY 0.872340 (-2925 3825);
DISPLAY INVISIBLE (-2925 3825);
FORCEPROP 1 LAST PATH I207
J 0
(-3252 3950);
DISPLAY 0.872340 (-3252 3950);
PAINT GREEN (-3252 3950);
DISPLAY INVISIBLE (-3252 3950);
FORCEADD TAP..1
(-3250 3850);
FORCEPROP 3 LASTPIN (-3300 3850) SIG_NAME M_I_CPU1_SA_DQS_DN<4>
J 0
(-3290 3860);
DISPLAY 0.659574 (-3290 3860);
PAINT MONO (-3290 3860);
DISPLAY INVISIBLE (-3290 3860);
FORCEPROP 1 LASTPIN (-3300 3850) BN 4
J 0
(-3312 3858);
DISPLAY 0.489362 (-3312 3858);
PAINT GREEN (-3312 3858);
FORCEPROP 2 LAST CDS_LIB mstr_standard
J 0
(-3250 3850);
DISPLAY 0.723404 (-3250 3850);
PAINT MONO (-3250 3850);
DISPLAY INVISIBLE (-3250 3850);
FORCEPROP 1 LAST BODY_TYPE PLUMBING
J 0
(-3250 3900);
DISPLAY 0.872340 (-3250 3900);
PAINT GREEN (-3250 3900);
DISPLAY INVISIBLE (-3250 3900);
FORCEPROP 1 LAST HDL_TAP TRUE
J 0
(-2925 3725);
DISPLAY 0.872340 (-2925 3725);
DISPLAY INVISIBLE (-2925 3725);
FORCEPROP 1 LAST PATH I208
J 0
(-3252 3850);
DISPLAY 0.872340 (-3252 3850);
PAINT GREEN (-3252 3850);
DISPLAY INVISIBLE (-3252 3850);
FORCEADD TAP..1
(-3250 3650);
FORCEPROP 3 LASTPIN (-3300 3650) SIG_NAME M_I_CPU1_SA_DQS_DN<2>
J 0
(-3290 3660);
DISPLAY 0.659574 (-3290 3660);
PAINT MONO (-3290 3660);
DISPLAY INVISIBLE (-3290 3660);
FORCEPROP 1 LASTPIN (-3300 3650) BN 2
J 0
(-3312 3658);
DISPLAY 0.489362 (-3312 3658);
PAINT GREEN (-3312 3658);
FORCEPROP 2 LAST CDS_LIB mstr_standard
J 0
(-3250 3650);
DISPLAY 0.723404 (-3250 3650);
PAINT MONO (-3250 3650);
DISPLAY INVISIBLE (-3250 3650);
FORCEPROP 1 LAST BODY_TYPE PLUMBING
J 0
(-3250 3700);
DISPLAY 0.872340 (-3250 3700);
PAINT GREEN (-3250 3700);
DISPLAY INVISIBLE (-3250 3700);
FORCEPROP 1 LAST HDL_TAP TRUE
J 0
(-2925 3525);
DISPLAY 0.872340 (-2925 3525);
DISPLAY INVISIBLE (-2925 3525);
FORCEPROP 1 LAST PATH I209
J 0
(-3252 3650);
DISPLAY 0.872340 (-3252 3650);
PAINT GREEN (-3252 3650);
DISPLAY INVISIBLE (-3252 3650);
FORCEADD OFFPAGE..1
(-8275 5000);
FORCEPROP 2 LAST $XR0 45 
J 0
(-8526 5000);
DISPLAY 0.638298 (-8526 5000);
PAINT MONO (-8526 5000);
FORCEPROP 2 LAST PATH I21
J 0
(-8525 5050);
DISPLAY 1.021277 (-8525 5050);
DISPLAY INVISIBLE (-8525 5050);
FORCEPROP 1 LAST COMMENT_BODY TRUE
J 0
(-8150 4900);
DISPLAY 0.872340 (-8150 4900);
PAINT GREEN (-8150 4900);
DISPLAY INVISIBLE (-8150 4900);
FORCEPROP 1 LAST OFFPAGE TRUE
J 0
(-7950 4875);
DISPLAY 0.872340 (-7950 4875);
PAINT GREEN (-7950 4875);
DISPLAY INVISIBLE (-7950 4875);
FORCEPROP 2 LAST CDS_LIB mstr_standard
J 0
(-8275 5000);
DISPLAY 0.723404 (-8275 5000);
PAINT MONO (-8275 5000);
DISPLAY INVISIBLE (-8275 5000);
FORCEADD TAP..1
(-3250 3750);
FORCEPROP 3 LASTPIN (-3300 3750) SIG_NAME M_I_CPU1_SA_DQS_DN<3>
J 0
(-3290 3760);
DISPLAY 0.659574 (-3290 3760);
PAINT MONO (-3290 3760);
DISPLAY INVISIBLE (-3290 3760);
FORCEPROP 1 LASTPIN (-3300 3750) BN 3
J 0
(-3312 3758);
DISPLAY 0.489362 (-3312 3758);
PAINT GREEN (-3312 3758);
FORCEPROP 2 LAST CDS_LIB mstr_standard
J 0
(-3250 3750);
DISPLAY 0.723404 (-3250 3750);
PAINT MONO (-3250 3750);
DISPLAY INVISIBLE (-3250 3750);
FORCEPROP 1 LAST BODY_TYPE PLUMBING
J 0
(-3250 3800);
DISPLAY 0.872340 (-3250 3800);
PAINT GREEN (-3250 3800);
DISPLAY INVISIBLE (-3250 3800);
FORCEPROP 1 LAST HDL_TAP TRUE
J 0
(-2925 3625);
DISPLAY 0.872340 (-2925 3625);
DISPLAY INVISIBLE (-2925 3625);
FORCEPROP 1 LAST PATH I210
J 0
(-3252 3750);
DISPLAY 0.872340 (-3252 3750);
PAINT GREEN (-3252 3750);
DISPLAY INVISIBLE (-3252 3750);
FORCEADD TAP..1
(-3450 4200);
FORCEPROP 3 LASTPIN (-3500 4200) SIG_NAME M_I_CPU1_SA_DQS_DP<7>
J 0
(-3490 4210);
DISPLAY 0.659574 (-3490 4210);
PAINT MONO (-3490 4210);
DISPLAY INVISIBLE (-3490 4210);
FORCEPROP 1 LASTPIN (-3500 4200) BN 7
J 0
(-3512 4208);
DISPLAY 0.489362 (-3512 4208);
PAINT GREEN (-3512 4208);
FORCEPROP 2 LAST CDS_LIB mstr_standard
J 0
(-3450 4200);
DISPLAY 0.723404 (-3450 4200);
PAINT MONO (-3450 4200);
DISPLAY INVISIBLE (-3450 4200);
FORCEPROP 1 LAST BODY_TYPE PLUMBING
J 0
(-3450 4250);
DISPLAY 0.872340 (-3450 4250);
PAINT GREEN (-3450 4250);
DISPLAY INVISIBLE (-3450 4250);
FORCEPROP 1 LAST HDL_TAP TRUE
J 0
(-3125 4075);
DISPLAY 0.872340 (-3125 4075);
DISPLAY INVISIBLE (-3125 4075);
FORCEPROP 1 LAST PATH I211
J 0
(-3452 4200);
DISPLAY 0.872340 (-3452 4200);
PAINT GREEN (-3452 4200);
DISPLAY INVISIBLE (-3452 4200);
FORCEADD TAP..1
(-3450 4100);
FORCEPROP 3 LASTPIN (-3500 4100) SIG_NAME M_I_CPU1_SA_DQS_DP<6>
J 0
(-3490 4110);
DISPLAY 0.659574 (-3490 4110);
PAINT MONO (-3490 4110);
DISPLAY INVISIBLE (-3490 4110);
FORCEPROP 1 LASTPIN (-3500 4100) BN 6
J 0
(-3512 4108);
DISPLAY 0.489362 (-3512 4108);
PAINT GREEN (-3512 4108);
FORCEPROP 2 LAST CDS_LIB mstr_standard
J 0
(-3450 4100);
DISPLAY 0.723404 (-3450 4100);
PAINT MONO (-3450 4100);
DISPLAY INVISIBLE (-3450 4100);
FORCEPROP 1 LAST BODY_TYPE PLUMBING
J 0
(-3450 4150);
DISPLAY 0.872340 (-3450 4150);
PAINT GREEN (-3450 4150);
DISPLAY INVISIBLE (-3450 4150);
FORCEPROP 1 LAST HDL_TAP TRUE
J 0
(-3125 3975);
DISPLAY 0.872340 (-3125 3975);
DISPLAY INVISIBLE (-3125 3975);
FORCEPROP 1 LAST PATH I212
J 0
(-3452 4100);
DISPLAY 0.872340 (-3452 4100);
PAINT GREEN (-3452 4100);
DISPLAY INVISIBLE (-3452 4100);
FORCEADD TAP..1
(-3450 3900);
FORCEPROP 3 LASTPIN (-3500 3900) SIG_NAME M_I_CPU1_SA_DQS_DP<4>
J 0
(-3490 3910);
DISPLAY 0.659574 (-3490 3910);
PAINT MONO (-3490 3910);
DISPLAY INVISIBLE (-3490 3910);
FORCEPROP 1 LASTPIN (-3500 3900) BN 4
J 0
(-3512 3908);
DISPLAY 0.489362 (-3512 3908);
PAINT GREEN (-3512 3908);
FORCEPROP 2 LAST CDS_LIB mstr_standard
J 0
(-3450 3900);
DISPLAY 0.723404 (-3450 3900);
PAINT MONO (-3450 3900);
DISPLAY INVISIBLE (-3450 3900);
FORCEPROP 1 LAST BODY_TYPE PLUMBING
J 0
(-3450 3950);
DISPLAY 0.872340 (-3450 3950);
PAINT GREEN (-3450 3950);
DISPLAY INVISIBLE (-3450 3950);
FORCEPROP 1 LAST HDL_TAP TRUE
J 0
(-3125 3775);
DISPLAY 0.872340 (-3125 3775);
DISPLAY INVISIBLE (-3125 3775);
FORCEPROP 1 LAST PATH I213
J 0
(-3452 3900);
DISPLAY 0.872340 (-3452 3900);
PAINT GREEN (-3452 3900);
DISPLAY INVISIBLE (-3452 3900);
FORCEADD TAP..1
(-3450 4000);
FORCEPROP 3 LASTPIN (-3500 4000) SIG_NAME M_I_CPU1_SA_DQS_DP<5>
J 0
(-3490 4010);
DISPLAY 0.659574 (-3490 4010);
PAINT MONO (-3490 4010);
DISPLAY INVISIBLE (-3490 4010);
FORCEPROP 1 LASTPIN (-3500 4000) BN 5
J 0
(-3512 4008);
DISPLAY 0.489362 (-3512 4008);
PAINT GREEN (-3512 4008);
FORCEPROP 2 LAST CDS_LIB mstr_standard
J 0
(-3450 4000);
DISPLAY 0.723404 (-3450 4000);
PAINT MONO (-3450 4000);
DISPLAY INVISIBLE (-3450 4000);
FORCEPROP 1 LAST BODY_TYPE PLUMBING
J 0
(-3450 4050);
DISPLAY 0.872340 (-3450 4050);
PAINT GREEN (-3450 4050);
DISPLAY INVISIBLE (-3450 4050);
FORCEPROP 1 LAST HDL_TAP TRUE
J 0
(-3125 3875);
DISPLAY 0.872340 (-3125 3875);
DISPLAY INVISIBLE (-3125 3875);
FORCEPROP 1 LAST PATH I214
J 0
(-3452 4000);
DISPLAY 0.872340 (-3452 4000);
PAINT GREEN (-3452 4000);
DISPLAY INVISIBLE (-3452 4000);
FORCEADD TAP..1
(-3450 3700);
FORCEPROP 3 LASTPIN (-3500 3700) SIG_NAME M_I_CPU1_SA_DQS_DP<2>
J 0
(-3490 3710);
DISPLAY 0.659574 (-3490 3710);
PAINT MONO (-3490 3710);
DISPLAY INVISIBLE (-3490 3710);
FORCEPROP 1 LASTPIN (-3500 3700) BN 2
J 0
(-3512 3708);
DISPLAY 0.489362 (-3512 3708);
PAINT GREEN (-3512 3708);
FORCEPROP 2 LAST CDS_LIB mstr_standard
J 0
(-3450 3700);
DISPLAY 0.723404 (-3450 3700);
PAINT MONO (-3450 3700);
DISPLAY INVISIBLE (-3450 3700);
FORCEPROP 1 LAST BODY_TYPE PLUMBING
J 0
(-3450 3750);
DISPLAY 0.872340 (-3450 3750);
PAINT GREEN (-3450 3750);
DISPLAY INVISIBLE (-3450 3750);
FORCEPROP 1 LAST HDL_TAP TRUE
J 0
(-3125 3575);
DISPLAY 0.872340 (-3125 3575);
DISPLAY INVISIBLE (-3125 3575);
FORCEPROP 1 LAST PATH I215
J 0
(-3452 3700);
DISPLAY 0.872340 (-3452 3700);
PAINT GREEN (-3452 3700);
DISPLAY INVISIBLE (-3452 3700);
FORCEADD TAP..1
(-3450 3600);
FORCEPROP 3 LASTPIN (-3500 3600) SIG_NAME M_I_CPU1_SA_DQS_DP<1>
J 0
(-3490 3610);
DISPLAY 0.659574 (-3490 3610);
PAINT MONO (-3490 3610);
DISPLAY INVISIBLE (-3490 3610);
FORCEPROP 1 LASTPIN (-3500 3600) BN 1
J 0
(-3512 3608);
DISPLAY 0.489362 (-3512 3608);
PAINT GREEN (-3512 3608);
FORCEPROP 2 LAST CDS_LIB mstr_standard
J 0
(-3450 3600);
DISPLAY 0.723404 (-3450 3600);
PAINT MONO (-3450 3600);
DISPLAY INVISIBLE (-3450 3600);
FORCEPROP 1 LAST BODY_TYPE PLUMBING
J 0
(-3450 3650);
DISPLAY 0.872340 (-3450 3650);
PAINT GREEN (-3450 3650);
DISPLAY INVISIBLE (-3450 3650);
FORCEPROP 1 LAST HDL_TAP TRUE
J 0
(-3125 3475);
DISPLAY 0.872340 (-3125 3475);
DISPLAY INVISIBLE (-3125 3475);
FORCEPROP 1 LAST PATH I216
J 0
(-3452 3600);
DISPLAY 0.872340 (-3452 3600);
PAINT GREEN (-3452 3600);
DISPLAY INVISIBLE (-3452 3600);
FORCEADD TAP..1
(-3450 3500);
FORCEPROP 3 LASTPIN (-3500 3500) SIG_NAME M_I_CPU1_SA_DQS_DP<0>
J 0
(-3490 3510);
DISPLAY 0.659574 (-3490 3510);
PAINT MONO (-3490 3510);
DISPLAY INVISIBLE (-3490 3510);
FORCEPROP 1 LASTPIN (-3500 3500) BN 0
J 0
(-3512 3508);
DISPLAY 0.489362 (-3512 3508);
PAINT GREEN (-3512 3508);
FORCEPROP 2 LAST CDS_LIB mstr_standard
J 0
(-3450 3500);
DISPLAY 0.723404 (-3450 3500);
PAINT MONO (-3450 3500);
DISPLAY INVISIBLE (-3450 3500);
FORCEPROP 1 LAST BODY_TYPE PLUMBING
J 0
(-3450 3550);
DISPLAY 0.872340 (-3450 3550);
PAINT GREEN (-3450 3550);
DISPLAY INVISIBLE (-3450 3550);
FORCEPROP 1 LAST HDL_TAP TRUE
J 0
(-3125 3375);
DISPLAY 0.872340 (-3125 3375);
DISPLAY INVISIBLE (-3125 3375);
FORCEPROP 1 LAST PATH I217
J 0
(-3452 3500);
DISPLAY 0.872340 (-3452 3500);
PAINT GREEN (-3452 3500);
DISPLAY INVISIBLE (-3452 3500);
FORCEADD TAP..1
(-3450 3250);
FORCEPROP 3 LASTPIN (-3500 3250) SIG_NAME M_I_CPU1_SB_DQS_DP<8>
J 0
(-3490 3260);
DISPLAY 0.659574 (-3490 3260);
PAINT MONO (-3490 3260);
DISPLAY INVISIBLE (-3490 3260);
FORCEPROP 1 LASTPIN (-3500 3250) BN 8
J 0
(-3512 3258);
DISPLAY 0.489362 (-3512 3258);
PAINT GREEN (-3512 3258);
FORCEPROP 2 LAST CDS_LIB mstr_standard
J 0
(-3450 3250);
DISPLAY 0.723404 (-3450 3250);
PAINT MONO (-3450 3250);
DISPLAY INVISIBLE (-3450 3250);
FORCEPROP 1 LAST BODY_TYPE PLUMBING
J 0
(-3450 3300);
DISPLAY 0.872340 (-3450 3300);
PAINT GREEN (-3450 3300);
DISPLAY INVISIBLE (-3450 3300);
FORCEPROP 1 LAST HDL_TAP TRUE
J 0
(-3125 3125);
DISPLAY 0.872340 (-3125 3125);
DISPLAY INVISIBLE (-3125 3125);
FORCEPROP 1 LAST PATH I218
J 0
(-3452 3250);
DISPLAY 0.872340 (-3452 3250);
PAINT GREEN (-3452 3250);
DISPLAY INVISIBLE (-3452 3250);
FORCEADD TAP..1
(-3450 3350);
FORCEPROP 3 LASTPIN (-3500 3350) SIG_NAME M_I_CPU1_SB_DQS_DP<9>
J 0
(-3490 3360);
DISPLAY 0.659574 (-3490 3360);
PAINT MONO (-3490 3360);
DISPLAY INVISIBLE (-3490 3360);
FORCEPROP 1 LASTPIN (-3500 3350) BN 9
J 0
(-3512 3358);
DISPLAY 0.489362 (-3512 3358);
PAINT GREEN (-3512 3358);
FORCEPROP 2 LAST CDS_LIB mstr_standard
J 0
(-3450 3350);
DISPLAY 0.723404 (-3450 3350);
PAINT MONO (-3450 3350);
DISPLAY INVISIBLE (-3450 3350);
FORCEPROP 1 LAST BODY_TYPE PLUMBING
J 0
(-3450 3400);
DISPLAY 0.872340 (-3450 3400);
PAINT GREEN (-3450 3400);
DISPLAY INVISIBLE (-3450 3400);
FORCEPROP 1 LAST HDL_TAP TRUE
J 0
(-3125 3225);
DISPLAY 0.872340 (-3125 3225);
DISPLAY INVISIBLE (-3125 3225);
FORCEPROP 1 LAST PATH I219
J 0
(-3452 3350);
DISPLAY 0.872340 (-3452 3350);
PAINT GREEN (-3452 3350);
DISPLAY INVISIBLE (-3452 3350);
FORCEADD SCONN288_DDR506112002KQ..1
(-6825 3600);
FORCEPROP 1 LAST LOCATION J100
J 0
(-7275 5675);
DISPLAY 0.468085 (-7275 5675);
PAINT SKYBLUE (-7275 5675);
FORCEPROP 0 LAST $SEC 1
J 0
(-7275 5825);
DISPLAY 0.680851 (-7275 5825);
PAINT MONO (-7275 5825);
DISPLAY INVISIBLE (-7275 5825);
FORCEPROP 2 LAST CDS_SEC 1
J 0
(-7275 5825);
DISPLAY 1.021277 (-7275 5825);
DISPLAY INVISIBLE (-7275 5825);
FORCEPROP 0 LASTPIN (-7425 3000) $PN 62
J 2
(-7435 3010);
DISPLAY 0.680851 (-7435 3010);
PAINT MONO (-7435 3010);
FORCEPROP 0 LASTPIN (-7425 5050) $PN 66
J 2
(-7435 5060);
DISPLAY 0.680851 (-7435 5060);
PAINT MONO (-7435 5060);
FORCEPROP 0 LASTPIN (-7425 4650) $PN 76
J 2
(-7435 4660);
DISPLAY 0.680851 (-7435 4660);
PAINT MONO (-7435 4660);
FORCEPROP 0 LASTPIN (-7425 5100) $PN 211
J 2
(-7435 5110);
DISPLAY 0.680851 (-7435 5110);
PAINT MONO (-7435 5110);
FORCEPROP 0 LASTPIN (-7425 4700) $PN 221
J 2
(-7435 4710);
DISPLAY 0.680851 (-7435 4710);
PAINT MONO (-7435 4710);
FORCEPROP 0 LASTPIN (-7425 5150) $PN 68
J 2
(-7435 5160);
DISPLAY 0.680851 (-7435 5160);
PAINT MONO (-7435 5160);
FORCEPROP 0 LASTPIN (-7425 4750) $PN 78
J 2
(-7435 4760);
DISPLAY 0.680851 (-7435 4760);
PAINT MONO (-7435 4760);
FORCEPROP 0 LASTPIN (-7425 5200) $PN 213
J 2
(-7435 5210);
DISPLAY 0.680851 (-7435 5210);
PAINT MONO (-7435 5210);
FORCEPROP 0 LASTPIN (-7425 4800) $PN 223
J 2
(-7435 4810);
DISPLAY 0.680851 (-7435 4810);
PAINT MONO (-7435 4810);
FORCEPROP 0 LASTPIN (-7425 5250) $PN 70
J 2
(-7435 5260);
DISPLAY 0.680851 (-7435 5260);
PAINT MONO (-7435 5260);
FORCEPROP 0 LASTPIN (-7425 4850) $PN 80
J 2
(-7435 4860);
DISPLAY 0.680851 (-7435 4860);
PAINT MONO (-7435 4860);
FORCEPROP 0 LASTPIN (-7425 5300) $PN 215
J 2
(-7435 5310);
DISPLAY 0.680851 (-7435 5310);
PAINT MONO (-7435 5310);
FORCEPROP 0 LASTPIN (-7425 4900) $PN 225
J 2
(-7435 4910);
DISPLAY 0.680851 (-7435 4910);
PAINT MONO (-7435 4910);
FORCEPROP 0 LASTPIN (-7425 5350) $PN 72
J 2
(-7435 5360);
DISPLAY 0.680851 (-7435 5360);
PAINT MONO (-7435 5360);
FORCEPROP 0 LASTPIN (-7425 4950) $PN 82
J 2
(-7435 4960);
DISPLAY 0.680851 (-7435 4960);
PAINT MONO (-7435 4960);
FORCEPROP 0 LASTPIN (-7425 3600) $PN 51
J 2
(-7435 3610);
DISPLAY 0.680851 (-7435 3610);
PAINT MONO (-7435 3610);
FORCEPROP 0 LASTPIN (-7425 3150) $PN 96
J 2
(-7435 3160);
DISPLAY 0.680851 (-7435 3160);
PAINT MONO (-7435 3160);
FORCEPROP 0 LASTPIN (-7425 3650) $PN 53
J 2
(-7435 3660);
DISPLAY 0.680851 (-7435 3660);
PAINT MONO (-7435 3660);
FORCEPROP 0 LASTPIN (-7425 3200) $PN 98
J 2
(-7435 3210);
DISPLAY 0.680851 (-7435 3210);
PAINT MONO (-7435 3210);
FORCEPROP 0 LASTPIN (-7425 3700) $PN 196
J 2
(-7435 3710);
DISPLAY 0.680851 (-7435 3710);
PAINT MONO (-7435 3710);
FORCEPROP 0 LASTPIN (-7425 3250) $PN 241
J 2
(-7435 3260);
DISPLAY 0.680851 (-7435 3260);
PAINT MONO (-7435 3260);
FORCEPROP 0 LASTPIN (-7425 3750) $PN 198
J 2
(-7435 3760);
DISPLAY 0.680851 (-7435 3760);
PAINT MONO (-7435 3760);
FORCEPROP 0 LASTPIN (-7425 3300) $PN 243
J 2
(-7435 3310);
DISPLAY 0.680851 (-7435 3310);
PAINT MONO (-7435 3310);
FORCEPROP 0 LASTPIN (-7425 3800) $PN 58
J 2
(-7435 3810);
DISPLAY 0.680851 (-7435 3810);
PAINT MONO (-7435 3810);
FORCEPROP 0 LASTPIN (-7425 3350) $PN 89
J 2
(-7435 3360);
DISPLAY 0.680851 (-7435 3360);
PAINT MONO (-7435 3360);
FORCEPROP 0 LASTPIN (-7425 3850) $PN 60
J 2
(-7435 3860);
DISPLAY 0.680851 (-7435 3860);
PAINT MONO (-7435 3860);
FORCEPROP 0 LASTPIN (-7425 3400) $PN 91
J 2
(-7435 3410);
DISPLAY 0.680851 (-7435 3410);
PAINT MONO (-7435 3410);
FORCEPROP 0 LASTPIN (-7425 3900) $PN 203
J 2
(-7435 3910);
DISPLAY 0.680851 (-7435 3910);
PAINT MONO (-7435 3910);
FORCEPROP 0 LASTPIN (-7425 3450) $PN 234
J 2
(-7435 3460);
DISPLAY 0.680851 (-7435 3460);
PAINT MONO (-7435 3460);
FORCEPROP 0 LASTPIN (-7425 3950) $PN 205
J 2
(-7435 3960);
DISPLAY 0.680851 (-7435 3960);
PAINT MONO (-7435 3960);
FORCEPROP 0 LASTPIN (-7425 3500) $PN 236
J 2
(-7435 3510);
DISPLAY 0.680851 (-7435 3510);
PAINT MONO (-7435 3510);
FORCEPROP 0 LASTPIN (-7425 4050) $PN 218
J 2
(-7435 4060);
DISPLAY 0.680851 (-7435 4060);
PAINT MONO (-7435 4060);
FORCEPROP 0 LASTPIN (-7425 4100) $PN 217
J 2
(-7435 4110);
DISPLAY 0.680851 (-7435 4110);
PAINT MONO (-7435 4110);
FORCEPROP 0 LASTPIN (-7425 4350) $PN 64
J 2
(-7435 4360);
DISPLAY 0.680851 (-7435 4360);
PAINT MONO (-7435 4360);
FORCEPROP 0 LASTPIN (-7425 4200) $PN 84
J 2
(-7435 4210);
DISPLAY 0.680851 (-7435 4210);
PAINT MONO (-7435 4210);
FORCEPROP 0 LASTPIN (-7425 4400) $PN 209
J 2
(-7435 4410);
DISPLAY 0.680851 (-7435 4410);
PAINT MONO (-7435 4410);
FORCEPROP 0 LASTPIN (-7425 4250) $PN 229
J 2
(-7435 4260);
DISPLAY 0.680851 (-7435 4260);
PAINT MONO (-7435 4260);
FORCEPROP 0 LASTPIN (-6225 3800) $PN 7
J 0
(-6215 3810);
DISPLAY 0.680851 (-6215 3810);
PAINT MONO (-6215 3810);
FORCEPROP 0 LASTPIN (-6225 2150) $PN 100
J 0
(-6215 2160);
DISPLAY 0.680851 (-6215 2160);
PAINT MONO (-6215 2160);
FORCEPROP 0 LASTPIN (-6225 3850) $PN 9
J 0
(-6215 3860);
DISPLAY 0.680851 (-6215 3860);
PAINT MONO (-6215 3860);
FORCEPROP 0 LASTPIN (-6225 2200) $PN 102
J 0
(-6215 2210);
DISPLAY 0.680851 (-6215 2210);
PAINT MONO (-6215 2210);
FORCEPROP 0 LASTPIN (-6225 3900) $PN 152
J 0
(-6215 3910);
DISPLAY 0.680851 (-6215 3910);
PAINT MONO (-6215 3910);
FORCEPROP 0 LASTPIN (-6225 2250) $PN 245
J 0
(-6215 2260);
DISPLAY 0.680851 (-6215 2260);
PAINT MONO (-6215 2260);
FORCEPROP 0 LASTPIN (-6225 3950) $PN 154
J 0
(-6215 3960);
DISPLAY 0.680851 (-6215 3960);
PAINT MONO (-6215 3960);
FORCEPROP 0 LASTPIN (-6225 2300) $PN 247
J 0
(-6215 2310);
DISPLAY 0.680851 (-6215 2310);
PAINT MONO (-6215 2310);
FORCEPROP 0 LASTPIN (-6225 4000) $PN 14
J 0
(-6215 4010);
DISPLAY 0.680851 (-6215 4010);
PAINT MONO (-6215 4010);
FORCEPROP 0 LASTPIN (-6225 2350) $PN 107
J 0
(-6215 2360);
DISPLAY 0.680851 (-6215 2360);
PAINT MONO (-6215 2360);
FORCEPROP 0 LASTPIN (-6225 4050) $PN 16
J 0
(-6215 4060);
DISPLAY 0.680851 (-6215 4060);
PAINT MONO (-6215 4060);
FORCEPROP 0 LASTPIN (-6225 2400) $PN 109
J 0
(-6215 2410);
DISPLAY 0.680851 (-6215 2410);
PAINT MONO (-6215 2410);
FORCEPROP 0 LASTPIN (-6225 4100) $PN 159
J 0
(-6215 4110);
DISPLAY 0.680851 (-6215 4110);
PAINT MONO (-6215 4110);
FORCEPROP 0 LASTPIN (-6225 2450) $PN 252
J 0
(-6215 2460);
DISPLAY 0.680851 (-6215 2460);
PAINT MONO (-6215 2460);
FORCEPROP 0 LASTPIN (-6225 4150) $PN 161
J 0
(-6215 4160);
DISPLAY 0.680851 (-6215 4160);
PAINT MONO (-6215 4160);
FORCEPROP 0 LASTPIN (-6225 2500) $PN 254
J 0
(-6215 2510);
DISPLAY 0.680851 (-6215 2510);
PAINT MONO (-6215 2510);
FORCEPROP 0 LASTPIN (-6225 4200) $PN 18
J 0
(-6215 4210);
DISPLAY 0.680851 (-6215 4210);
PAINT MONO (-6215 4210);
FORCEPROP 0 LASTPIN (-6225 2550) $PN 111
J 0
(-6215 2560);
DISPLAY 0.680851 (-6215 2560);
PAINT MONO (-6215 2560);
FORCEPROP 0 LASTPIN (-6225 4250) $PN 20
J 0
(-6215 4260);
DISPLAY 0.680851 (-6215 4260);
PAINT MONO (-6215 4260);
FORCEPROP 0 LASTPIN (-6225 2600) $PN 113
J 0
(-6215 2610);
DISPLAY 0.680851 (-6215 2610);
PAINT MONO (-6215 2610);
FORCEPROP 0 LASTPIN (-6225 4300) $PN 163
J 0
(-6215 4310);
DISPLAY 0.680851 (-6215 4310);
PAINT MONO (-6215 4310);
FORCEPROP 0 LASTPIN (-6225 2650) $PN 256
J 0
(-6215 2660);
DISPLAY 0.680851 (-6215 2660);
PAINT MONO (-6215 2660);
FORCEPROP 0 LASTPIN (-6225 4350) $PN 165
J 0
(-6215 4360);
DISPLAY 0.680851 (-6215 4360);
PAINT MONO (-6215 4360);
FORCEPROP 0 LASTPIN (-6225 2700) $PN 258
J 0
(-6215 2710);
DISPLAY 0.680851 (-6215 2710);
PAINT MONO (-6215 2710);
FORCEPROP 0 LASTPIN (-6225 4400) $PN 25
J 0
(-6215 4410);
DISPLAY 0.680851 (-6215 4410);
PAINT MONO (-6215 4410);
FORCEPROP 0 LASTPIN (-6225 2750) $PN 118
J 0
(-6215 2760);
DISPLAY 0.680851 (-6215 2760);
PAINT MONO (-6215 2760);
FORCEPROP 0 LASTPIN (-6225 4450) $PN 27
J 0
(-6215 4460);
DISPLAY 0.680851 (-6215 4460);
PAINT MONO (-6215 4460);
FORCEPROP 0 LASTPIN (-6225 2800) $PN 120
J 0
(-6215 2810);
DISPLAY 0.680851 (-6215 2810);
PAINT MONO (-6215 2810);
FORCEPROP 0 LASTPIN (-6225 4500) $PN 170
J 0
(-6215 4510);
DISPLAY 0.680851 (-6215 4510);
PAINT MONO (-6215 4510);
FORCEPROP 0 LASTPIN (-6225 2850) $PN 263
J 0
(-6215 2860);
DISPLAY 0.680851 (-6215 2860);
PAINT MONO (-6215 2860);
FORCEPROP 0 LASTPIN (-6225 4550) $PN 172
J 0
(-6215 4560);
DISPLAY 0.680851 (-6215 4560);
PAINT MONO (-6215 4560);
FORCEPROP 0 LASTPIN (-6225 2900) $PN 265
J 0
(-6215 2910);
DISPLAY 0.680851 (-6215 2910);
PAINT MONO (-6215 2910);
FORCEPROP 0 LASTPIN (-6225 4600) $PN 29
J 0
(-6215 4610);
DISPLAY 0.680851 (-6215 4610);
PAINT MONO (-6215 4610);
FORCEPROP 0 LASTPIN (-6225 2950) $PN 122
J 0
(-6215 2960);
DISPLAY 0.680851 (-6215 2960);
PAINT MONO (-6215 2960);
FORCEPROP 0 LASTPIN (-6225 4650) $PN 31
J 0
(-6215 4660);
DISPLAY 0.680851 (-6215 4660);
PAINT MONO (-6215 4660);
FORCEPROP 0 LASTPIN (-6225 3000) $PN 124
J 0
(-6215 3010);
DISPLAY 0.680851 (-6215 3010);
PAINT MONO (-6215 3010);
FORCEPROP 0 LASTPIN (-6225 4700) $PN 174
J 0
(-6215 4710);
DISPLAY 0.680851 (-6215 4710);
PAINT MONO (-6215 4710);
FORCEPROP 0 LASTPIN (-6225 3050) $PN 267
J 0
(-6215 3060);
DISPLAY 0.680851 (-6215 3060);
PAINT MONO (-6215 3060);
FORCEPROP 0 LASTPIN (-6225 4750) $PN 176
J 0
(-6215 4760);
DISPLAY 0.680851 (-6215 4760);
PAINT MONO (-6215 4760);
FORCEPROP 0 LASTPIN (-6225 3100) $PN 269
J 0
(-6215 3110);
DISPLAY 0.680851 (-6215 3110);
PAINT MONO (-6215 3110);
FORCEPROP 0 LASTPIN (-6225 4800) $PN 36
J 0
(-6215 4810);
DISPLAY 0.680851 (-6215 4810);
PAINT MONO (-6215 4810);
FORCEPROP 0 LASTPIN (-6225 3150) $PN 129
J 0
(-6215 3160);
DISPLAY 0.680851 (-6215 3160);
PAINT MONO (-6215 3160);
FORCEPROP 0 LASTPIN (-6225 4850) $PN 38
J 0
(-6215 4860);
DISPLAY 0.680851 (-6215 4860);
PAINT MONO (-6215 4860);
FORCEPROP 0 LASTPIN (-6225 3200) $PN 131
J 0
(-6215 3210);
DISPLAY 0.680851 (-6215 3210);
PAINT MONO (-6215 3210);
FORCEPROP 0 LASTPIN (-6225 4900) $PN 181
J 0
(-6215 4910);
DISPLAY 0.680851 (-6215 4910);
PAINT MONO (-6215 4910);
FORCEPROP 0 LASTPIN (-6225 3250) $PN 274
J 0
(-6215 3260);
DISPLAY 0.680851 (-6215 3260);
PAINT MONO (-6215 3260);
FORCEPROP 0 LASTPIN (-6225 4950) $PN 183
J 0
(-6215 4960);
DISPLAY 0.680851 (-6215 4960);
PAINT MONO (-6215 4960);
FORCEPROP 0 LASTPIN (-6225 3300) $PN 276
J 0
(-6215 3310);
DISPLAY 0.680851 (-6215 3310);
PAINT MONO (-6215 3310);
FORCEPROP 0 LASTPIN (-6225 5000) $PN 40
J 0
(-6215 5010);
DISPLAY 0.680851 (-6215 5010);
PAINT MONO (-6215 5010);
FORCEPROP 0 LASTPIN (-6225 3350) $PN 133
J 0
(-6215 3360);
DISPLAY 0.680851 (-6215 3360);
PAINT MONO (-6215 3360);
FORCEPROP 0 LASTPIN (-6225 5050) $PN 42
J 0
(-6215 5060);
DISPLAY 0.680851 (-6215 5060);
PAINT MONO (-6215 5060);
FORCEPROP 0 LASTPIN (-6225 3400) $PN 135
J 0
(-6215 3410);
DISPLAY 0.680851 (-6215 3410);
PAINT MONO (-6215 3410);
FORCEPROP 0 LASTPIN (-6225 5100) $PN 185
J 0
(-6215 5110);
DISPLAY 0.680851 (-6215 5110);
PAINT MONO (-6215 5110);
FORCEPROP 0 LASTPIN (-6225 3450) $PN 278
J 0
(-6215 3460);
DISPLAY 0.680851 (-6215 3460);
PAINT MONO (-6215 3460);
FORCEPROP 0 LASTPIN (-6225 5150) $PN 187
J 0
(-6215 5160);
DISPLAY 0.680851 (-6215 5160);
PAINT MONO (-6215 5160);
FORCEPROP 0 LASTPIN (-6225 3500) $PN 280
J 0
(-6215 3510);
DISPLAY 0.680851 (-6215 3510);
PAINT MONO (-6215 3510);
FORCEPROP 0 LASTPIN (-6225 5200) $PN 47
J 0
(-6215 5210);
DISPLAY 0.680851 (-6215 5210);
PAINT MONO (-6215 5210);
FORCEPROP 0 LASTPIN (-6225 3550) $PN 140
J 0
(-6215 3560);
DISPLAY 0.680851 (-6215 3560);
PAINT MONO (-6215 3560);
FORCEPROP 0 LASTPIN (-6225 5250) $PN 49
J 0
(-6215 5260);
DISPLAY 0.680851 (-6215 5260);
PAINT MONO (-6215 5260);
FORCEPROP 0 LASTPIN (-6225 3600) $PN 142
J 0
(-6215 3610);
DISPLAY 0.680851 (-6215 3610);
PAINT MONO (-6215 3610);
FORCEPROP 0 LASTPIN (-6225 5300) $PN 192
J 0
(-6215 5310);
DISPLAY 0.680851 (-6215 5310);
PAINT MONO (-6215 5310);
FORCEPROP 0 LASTPIN (-6225 3650) $PN 285
J 0
(-6215 3660);
DISPLAY 0.680851 (-6215 3660);
PAINT MONO (-6215 3660);
FORCEPROP 0 LASTPIN (-6225 5350) $PN 194
J 0
(-6215 5360);
DISPLAY 0.680851 (-6215 5360);
PAINT MONO (-6215 5360);
FORCEPROP 0 LASTPIN (-6225 3700) $PN 287
J 0
(-6215 3710);
DISPLAY 0.680851 (-6215 3710);
PAINT MONO (-6215 3710);
FORCEPROP 0 LASTPIN (-7425 2850) $PN 148
J 2
(-7435 2860);
DISPLAY 0.680851 (-7435 2860);
PAINT MONO (-7435 2860);
FORCEPROP 0 LASTPIN (-7425 2750) $PN 4
J 2
(-7435 2760);
DISPLAY 0.680851 (-7435 2760);
PAINT MONO (-7435 2760);
FORCEPROP 0 LASTPIN (-7425 2800) $PN 5
J 2
(-7435 2810);
DISPLAY 0.680851 (-7435 2810);
PAINT MONO (-7435 2810);
FORCEPROP 0 LASTPIN (-7425 1950) $PN 86
J 2
(-7435 1960);
DISPLAY 0.680851 (-7435 1960);
PAINT MONO (-7435 1960);
FORCEPROP 0 LASTPIN (-7425 1900) $PN 87
J 2
(-7435 1910);
DISPLAY 0.680851 (-7435 1910);
PAINT MONO (-7435 1910);
FORCEPROP 0 LASTPIN (-7425 4550) $PN 74
J 2
(-7435 4560);
DISPLAY 0.680851 (-7435 4560);
PAINT MONO (-7435 4560);
FORCEPROP 0 LASTPIN (-7425 4500) $PN 227
J 2
(-7435 4510);
DISPLAY 0.680851 (-7435 4510);
PAINT MONO (-7435 4510);
FORCEPROP 0 LASTPIN (-7425 2500) $PN 147
J 2
(-7435 2510);
DISPLAY 0.680851 (-7435 2510);
PAINT MONO (-7435 2510);
FORCEPROP 0 LASTPIN (-7425 3050) $PN 207
J 2
(-7435 3060);
DISPLAY 0.680851 (-7435 3060);
PAINT MONO (-7435 3060);
FORCEPROP 0 LASTPIN (-7425 2100) $PN 2
J 2
(-7435 2110);
DISPLAY 0.680851 (-7435 2110);
PAINT MONO (-7435 2110);
FORCEPROP 0 LASTPIN (-7425 2150) $PN 144
J 2
(-7435 2160);
DISPLAY 0.680851 (-7435 2160);
PAINT MONO (-7435 2160);
FORCEPROP 0 LASTPIN (-7425 2200) $PN 149
J 2
(-7435 2210);
DISPLAY 0.680851 (-7435 2210);
PAINT MONO (-7435 2210);
FORCEPROP 0 LASTPIN (-7425 2250) $PN 150
J 2
(-7435 2260);
DISPLAY 0.680851 (-7435 2260);
PAINT MONO (-7435 2260);
FORCEPROP 0 LASTPIN (-7425 2300) $PN 220
J 2
(-7435 2310);
DISPLAY 0.680851 (-7435 2310);
PAINT MONO (-7435 2310);
FORCEPROP 0 LASTPIN (-7425 2350) $PN 231
J 2
(-7435 2360);
DISPLAY 0.680851 (-7435 2360);
PAINT MONO (-7435 2360);
FORCEPROP 0 LASTPIN (-7425 2400) $PN 232
J 2
(-7435 2410);
DISPLAY 0.680851 (-7435 2410);
PAINT MONO (-7435 2410);
FORCEPROP 0 LASTPIN (-7425 2900) $PN 3
J 2
(-7435 2910);
DISPLAY 0.680851 (-7435 2910);
PAINT MONO (-7435 2910);
FORCEPROP 2 LAST PART_TYPE SMLF
J 0
(-7275 5775);
DISPLAY 1.021277 (-7275 5775);
FORCEPROP 1 LAST MATERIAL IO
J 0
(-7275 5525);
DISPLAY 0.468085 (-7275 5525);
PAINT SKYBLUE (-7275 5525);
FORCEPROP 2 LAST VALUE SCONN288_DDR506112002KQ
J 0
(-7275 5725);
DISPLAY 0.489362 (-7275 5725);
PAINT SKYBLUE (-7275 5725);
FORCEPROP 1 LAST PART_NUMBER DFHST8FS479
J 0
(-7275 5600);
DISPLAY 0.468085 (-7275 5600);
PAINT SKYBLUE (-7275 5600);
FORCEPROP 1 LAST CDS_LMAN_SYM_OUTLINE -450,1900,450,-1850
J 0
(-6825 3600);
DISPLAY 0.468085 (-6825 3600);
PAINT GREEN (-6825 3600);
DISPLAY INVISIBLE (-6825 3600);
FORCEPROP 1 LAST PATH I22
J 0
(-6825 3600);
DISPLAY 0.723404 (-6825 3600);
PAINT GREEN (-6825 3600);
DISPLAY INVISIBLE (-6825 3600);
FORCEPROP 1 LAST NEEDS_NO_SIZE TRUE
J 0
(-6825 3600);
DISPLAY 0.723404 (-6825 3600);
PAINT GREEN (-6825 3600);
DISPLAY INVISIBLE (-6825 3600);
FORCEPROP 2 LAST CDS_LIB pure_quanta
J 0
(-6825 3600);
DISPLAY INVISIBLE (-6825 3600);
FORCEADD TAP..1
(-3250 3200);
FORCEPROP 3 LASTPIN (-3300 3200) SIG_NAME M_I_CPU1_SB_DQS_DN<8>
J 0
(-3290 3210);
DISPLAY 0.659574 (-3290 3210);
PAINT MONO (-3290 3210);
DISPLAY INVISIBLE (-3290 3210);
FORCEPROP 1 LASTPIN (-3300 3200) BN 8
J 0
(-3312 3208);
DISPLAY 0.489362 (-3312 3208);
PAINT GREEN (-3312 3208);
FORCEPROP 2 LAST CDS_LIB mstr_standard
J 0
(-3250 3200);
DISPLAY 0.723404 (-3250 3200);
PAINT MONO (-3250 3200);
DISPLAY INVISIBLE (-3250 3200);
FORCEPROP 1 LAST BODY_TYPE PLUMBING
J 0
(-3250 3250);
DISPLAY 0.872340 (-3250 3250);
PAINT GREEN (-3250 3250);
DISPLAY INVISIBLE (-3250 3250);
FORCEPROP 1 LAST HDL_TAP TRUE
J 0
(-2925 3075);
DISPLAY 0.872340 (-2925 3075);
DISPLAY INVISIBLE (-2925 3075);
FORCEPROP 1 LAST PATH I220
J 0
(-3252 3200);
DISPLAY 0.872340 (-3252 3200);
PAINT GREEN (-3252 3200);
DISPLAY INVISIBLE (-3252 3200);
FORCEADD TAP..1
(-3250 3000);
FORCEPROP 3 LASTPIN (-3300 3000) SIG_NAME M_I_CPU1_SB_DQS_DN<6>
J 0
(-3290 3010);
DISPLAY 0.659574 (-3290 3010);
PAINT MONO (-3290 3010);
DISPLAY INVISIBLE (-3290 3010);
FORCEPROP 1 LASTPIN (-3300 3000) BN 6
J 0
(-3312 3008);
DISPLAY 0.489362 (-3312 3008);
PAINT GREEN (-3312 3008);
FORCEPROP 2 LAST CDS_LIB mstr_standard
J 0
(-3250 3000);
DISPLAY 0.723404 (-3250 3000);
PAINT MONO (-3250 3000);
DISPLAY INVISIBLE (-3250 3000);
FORCEPROP 1 LAST BODY_TYPE PLUMBING
J 0
(-3250 3050);
DISPLAY 0.872340 (-3250 3050);
PAINT GREEN (-3250 3050);
DISPLAY INVISIBLE (-3250 3050);
FORCEPROP 1 LAST HDL_TAP TRUE
J 0
(-2925 2875);
DISPLAY 0.872340 (-2925 2875);
DISPLAY INVISIBLE (-2925 2875);
FORCEPROP 1 LAST PATH I221
J 0
(-3252 3000);
DISPLAY 0.872340 (-3252 3000);
PAINT GREEN (-3252 3000);
DISPLAY INVISIBLE (-3252 3000);
FORCEADD TAP..1
(-3250 2900);
FORCEPROP 3 LASTPIN (-3300 2900) SIG_NAME M_I_CPU1_SB_DQS_DN<5>
J 0
(-3290 2910);
DISPLAY 0.659574 (-3290 2910);
PAINT MONO (-3290 2910);
DISPLAY INVISIBLE (-3290 2910);
FORCEPROP 1 LASTPIN (-3300 2900) BN 5
J 0
(-3312 2908);
DISPLAY 0.489362 (-3312 2908);
PAINT GREEN (-3312 2908);
FORCEPROP 2 LAST CDS_LIB mstr_standard
J 0
(-3250 2900);
DISPLAY 0.723404 (-3250 2900);
PAINT MONO (-3250 2900);
DISPLAY INVISIBLE (-3250 2900);
FORCEPROP 1 LAST BODY_TYPE PLUMBING
J 0
(-3250 2950);
DISPLAY 0.872340 (-3250 2950);
PAINT GREEN (-3250 2950);
DISPLAY INVISIBLE (-3250 2950);
FORCEPROP 1 LAST HDL_TAP TRUE
J 0
(-2925 2775);
DISPLAY 0.872340 (-2925 2775);
DISPLAY INVISIBLE (-2925 2775);
FORCEPROP 1 LAST PATH I222
J 0
(-3252 2900);
DISPLAY 0.872340 (-3252 2900);
PAINT GREEN (-3252 2900);
DISPLAY INVISIBLE (-3252 2900);
FORCEADD TAP..1
(-3250 2800);
FORCEPROP 3 LASTPIN (-3300 2800) SIG_NAME M_I_CPU1_SB_DQS_DN<4>
J 0
(-3290 2810);
DISPLAY 0.659574 (-3290 2810);
PAINT MONO (-3290 2810);
DISPLAY INVISIBLE (-3290 2810);
FORCEPROP 1 LASTPIN (-3300 2800) BN 4
J 0
(-3312 2808);
DISPLAY 0.489362 (-3312 2808);
PAINT GREEN (-3312 2808);
FORCEPROP 2 LAST CDS_LIB mstr_standard
J 0
(-3250 2800);
DISPLAY 0.723404 (-3250 2800);
PAINT MONO (-3250 2800);
DISPLAY INVISIBLE (-3250 2800);
FORCEPROP 1 LAST BODY_TYPE PLUMBING
J 0
(-3250 2850);
DISPLAY 0.872340 (-3250 2850);
PAINT GREEN (-3250 2850);
DISPLAY INVISIBLE (-3250 2850);
FORCEPROP 1 LAST HDL_TAP TRUE
J 0
(-2925 2675);
DISPLAY 0.872340 (-2925 2675);
DISPLAY INVISIBLE (-2925 2675);
FORCEPROP 1 LAST PATH I223
J 0
(-3252 2800);
DISPLAY 0.872340 (-3252 2800);
PAINT GREEN (-3252 2800);
DISPLAY INVISIBLE (-3252 2800);
FORCEADD TAP..1
(-3250 2700);
FORCEPROP 3 LASTPIN (-3300 2700) SIG_NAME M_I_CPU1_SB_DQS_DN<3>
J 0
(-3290 2710);
DISPLAY 0.659574 (-3290 2710);
PAINT MONO (-3290 2710);
DISPLAY INVISIBLE (-3290 2710);
FORCEPROP 1 LASTPIN (-3300 2700) BN 3
J 0
(-3312 2708);
DISPLAY 0.489362 (-3312 2708);
PAINT GREEN (-3312 2708);
FORCEPROP 2 LAST CDS_LIB mstr_standard
J 0
(-3250 2700);
DISPLAY 0.723404 (-3250 2700);
PAINT MONO (-3250 2700);
DISPLAY INVISIBLE (-3250 2700);
FORCEPROP 1 LAST BODY_TYPE PLUMBING
J 0
(-3250 2750);
DISPLAY 0.872340 (-3250 2750);
PAINT GREEN (-3250 2750);
DISPLAY INVISIBLE (-3250 2750);
FORCEPROP 1 LAST HDL_TAP TRUE
J 0
(-2925 2575);
DISPLAY 0.872340 (-2925 2575);
DISPLAY INVISIBLE (-2925 2575);
FORCEPROP 1 LAST PATH I224
J 0
(-3252 2700);
DISPLAY 0.872340 (-3252 2700);
PAINT GREEN (-3252 2700);
DISPLAY INVISIBLE (-3252 2700);
FORCEADD TAP..1
(-3250 2600);
FORCEPROP 3 LASTPIN (-3300 2600) SIG_NAME M_I_CPU1_SB_DQS_DN<2>
J 0
(-3290 2610);
DISPLAY 0.659574 (-3290 2610);
PAINT MONO (-3290 2610);
DISPLAY INVISIBLE (-3290 2610);
FORCEPROP 1 LASTPIN (-3300 2600) BN 2
J 0
(-3312 2608);
DISPLAY 0.489362 (-3312 2608);
PAINT GREEN (-3312 2608);
FORCEPROP 2 LAST CDS_LIB mstr_standard
J 0
(-3250 2600);
DISPLAY 0.723404 (-3250 2600);
PAINT MONO (-3250 2600);
DISPLAY INVISIBLE (-3250 2600);
FORCEPROP 1 LAST BODY_TYPE PLUMBING
J 0
(-3250 2650);
DISPLAY 0.872340 (-3250 2650);
PAINT GREEN (-3250 2650);
DISPLAY INVISIBLE (-3250 2650);
FORCEPROP 1 LAST HDL_TAP TRUE
J 0
(-2925 2475);
DISPLAY 0.872340 (-2925 2475);
DISPLAY INVISIBLE (-2925 2475);
FORCEPROP 1 LAST PATH I225
J 0
(-3252 2600);
DISPLAY 0.872340 (-3252 2600);
PAINT GREEN (-3252 2600);
DISPLAY INVISIBLE (-3252 2600);
FORCEADD TAP..1
(-3250 2500);
FORCEPROP 3 LASTPIN (-3300 2500) SIG_NAME M_I_CPU1_SB_DQS_DN<1>
J 0
(-3290 2510);
DISPLAY 0.659574 (-3290 2510);
PAINT MONO (-3290 2510);
DISPLAY INVISIBLE (-3290 2510);
FORCEPROP 1 LASTPIN (-3300 2500) BN 1
J 0
(-3312 2508);
DISPLAY 0.489362 (-3312 2508);
PAINT GREEN (-3312 2508);
FORCEPROP 2 LAST CDS_LIB mstr_standard
J 0
(-3250 2500);
DISPLAY 0.723404 (-3250 2500);
PAINT MONO (-3250 2500);
DISPLAY INVISIBLE (-3250 2500);
FORCEPROP 1 LAST BODY_TYPE PLUMBING
J 0
(-3250 2550);
DISPLAY 0.872340 (-3250 2550);
PAINT GREEN (-3250 2550);
DISPLAY INVISIBLE (-3250 2550);
FORCEPROP 1 LAST HDL_TAP TRUE
J 0
(-2925 2375);
DISPLAY 0.872340 (-2925 2375);
DISPLAY INVISIBLE (-2925 2375);
FORCEPROP 1 LAST PATH I226
J 0
(-3252 2500);
DISPLAY 0.872340 (-3252 2500);
PAINT GREEN (-3252 2500);
DISPLAY INVISIBLE (-3252 2500);
FORCEADD TAP..1
(-3250 2400);
FORCEPROP 3 LASTPIN (-3300 2400) SIG_NAME M_I_CPU1_SB_DQS_DN<0>
J 0
(-3290 2410);
DISPLAY 0.659574 (-3290 2410);
PAINT MONO (-3290 2410);
DISPLAY INVISIBLE (-3290 2410);
FORCEPROP 1 LASTPIN (-3300 2400) BN 0
J 0
(-3312 2408);
DISPLAY 0.489362 (-3312 2408);
PAINT GREEN (-3312 2408);
FORCEPROP 2 LAST CDS_LIB mstr_standard
J 0
(-3250 2400);
DISPLAY 0.723404 (-3250 2400);
PAINT MONO (-3250 2400);
DISPLAY INVISIBLE (-3250 2400);
FORCEPROP 1 LAST BODY_TYPE PLUMBING
J 0
(-3250 2450);
DISPLAY 0.872340 (-3250 2450);
PAINT GREEN (-3250 2450);
DISPLAY INVISIBLE (-3250 2450);
FORCEPROP 1 LAST HDL_TAP TRUE
J 0
(-2925 2275);
DISPLAY 0.872340 (-2925 2275);
DISPLAY INVISIBLE (-2925 2275);
FORCEPROP 1 LAST PATH I227
J 0
(-3252 2400);
DISPLAY 0.872340 (-3252 2400);
PAINT GREEN (-3252 2400);
DISPLAY INVISIBLE (-3252 2400);
FORCEADD TAP..1
(-3450 3150);
FORCEPROP 3 LASTPIN (-3500 3150) SIG_NAME M_I_CPU1_SB_DQS_DP<7>
J 0
(-3490 3160);
DISPLAY 0.659574 (-3490 3160);
PAINT MONO (-3490 3160);
DISPLAY INVISIBLE (-3490 3160);
FORCEPROP 1 LASTPIN (-3500 3150) BN 7
J 0
(-3512 3158);
DISPLAY 0.489362 (-3512 3158);
PAINT GREEN (-3512 3158);
FORCEPROP 2 LAST CDS_LIB mstr_standard
J 0
(-3450 3150);
DISPLAY 0.723404 (-3450 3150);
PAINT MONO (-3450 3150);
DISPLAY INVISIBLE (-3450 3150);
FORCEPROP 1 LAST BODY_TYPE PLUMBING
J 0
(-3450 3200);
DISPLAY 0.872340 (-3450 3200);
PAINT GREEN (-3450 3200);
DISPLAY INVISIBLE (-3450 3200);
FORCEPROP 1 LAST HDL_TAP TRUE
J 0
(-3125 3025);
DISPLAY 0.872340 (-3125 3025);
DISPLAY INVISIBLE (-3125 3025);
FORCEPROP 1 LAST PATH I228
J 0
(-3452 3150);
DISPLAY 0.872340 (-3452 3150);
PAINT GREEN (-3452 3150);
DISPLAY INVISIBLE (-3452 3150);
FORCEADD TAP..1
(-3450 3050);
FORCEPROP 3 LASTPIN (-3500 3050) SIG_NAME M_I_CPU1_SB_DQS_DP<6>
J 0
(-3490 3060);
DISPLAY 0.659574 (-3490 3060);
PAINT MONO (-3490 3060);
DISPLAY INVISIBLE (-3490 3060);
FORCEPROP 1 LASTPIN (-3500 3050) BN 6
J 0
(-3512 3058);
DISPLAY 0.489362 (-3512 3058);
PAINT GREEN (-3512 3058);
FORCEPROP 2 LAST CDS_LIB mstr_standard
J 0
(-3450 3050);
DISPLAY 0.723404 (-3450 3050);
PAINT MONO (-3450 3050);
DISPLAY INVISIBLE (-3450 3050);
FORCEPROP 1 LAST BODY_TYPE PLUMBING
J 0
(-3450 3100);
DISPLAY 0.872340 (-3450 3100);
PAINT GREEN (-3450 3100);
DISPLAY INVISIBLE (-3450 3100);
FORCEPROP 1 LAST HDL_TAP TRUE
J 0
(-3125 2925);
DISPLAY 0.872340 (-3125 2925);
DISPLAY INVISIBLE (-3125 2925);
FORCEPROP 1 LAST PATH I229
J 0
(-3452 3050);
DISPLAY 0.872340 (-3452 3050);
PAINT GREEN (-3452 3050);
DISPLAY INVISIBLE (-3452 3050);
FORCEADD TAP..1
R 2
(-7675 3150);
FORCEPROP 3 LASTPIN (-7625 3150) SIG_NAME M_I_CPU1_SB_CB<0>
J 0
(-7615 3160);
DISPLAY 0.659574 (-7615 3160);
PAINT MONO (-7615 3160);
DISPLAY INVISIBLE (-7615 3160);
FORCEPROP 1 LASTPIN (-7625 3150) BN 0
J 2
(-7613 3158);
DISPLAY 0.489362 (-7613 3158);
PAINT GREEN (-7613 3158);
FORCEPROP 2 LAST CDS_LIB mstr_standard
J 0
(-7675 3150);
DISPLAY 0.723404 (-7675 3150);
PAINT MONO (-7675 3150);
DISPLAY INVISIBLE (-7675 3150);
FORCEPROP 1 LAST BODY_TYPE PLUMBING
J 2
(-7675 3200);
DISPLAY 0.872340 (-7675 3200);
PAINT GREEN (-7675 3200);
DISPLAY INVISIBLE (-7675 3200);
FORCEPROP 1 LAST HDL_TAP TRUE
J 2
(-8000 3025);
DISPLAY 0.872340 (-8000 3025);
DISPLAY INVISIBLE (-8000 3025);
FORCEPROP 1 LAST PATH I23
J 2
(-7673 3150);
DISPLAY 0.872340 (-7673 3150);
PAINT GREEN (-7673 3150);
DISPLAY INVISIBLE (-7673 3150);
FORCEADD TAP..1
(-3450 2950);
FORCEPROP 3 LASTPIN (-3500 2950) SIG_NAME M_I_CPU1_SB_DQS_DP<5>
J 0
(-3490 2960);
DISPLAY 0.659574 (-3490 2960);
PAINT MONO (-3490 2960);
DISPLAY INVISIBLE (-3490 2960);
FORCEPROP 1 LASTPIN (-3500 2950) BN 5
J 0
(-3512 2958);
DISPLAY 0.489362 (-3512 2958);
PAINT GREEN (-3512 2958);
FORCEPROP 2 LAST CDS_LIB mstr_standard
J 0
(-3450 2950);
DISPLAY 0.723404 (-3450 2950);
PAINT MONO (-3450 2950);
DISPLAY INVISIBLE (-3450 2950);
FORCEPROP 1 LAST BODY_TYPE PLUMBING
J 0
(-3450 3000);
DISPLAY 0.872340 (-3450 3000);
PAINT GREEN (-3450 3000);
DISPLAY INVISIBLE (-3450 3000);
FORCEPROP 1 LAST HDL_TAP TRUE
J 0
(-3125 2825);
DISPLAY 0.872340 (-3125 2825);
DISPLAY INVISIBLE (-3125 2825);
FORCEPROP 1 LAST PATH I230
J 0
(-3452 2950);
DISPLAY 0.872340 (-3452 2950);
PAINT GREEN (-3452 2950);
DISPLAY INVISIBLE (-3452 2950);
FORCEADD TAP..1
(-3450 2750);
FORCEPROP 3 LASTPIN (-3500 2750) SIG_NAME M_I_CPU1_SB_DQS_DP<3>
J 0
(-3490 2760);
DISPLAY 0.659574 (-3490 2760);
PAINT MONO (-3490 2760);
DISPLAY INVISIBLE (-3490 2760);
FORCEPROP 1 LASTPIN (-3500 2750) BN 3
J 0
(-3512 2758);
DISPLAY 0.489362 (-3512 2758);
PAINT GREEN (-3512 2758);
FORCEPROP 2 LAST CDS_LIB mstr_standard
J 0
(-3450 2750);
DISPLAY 0.723404 (-3450 2750);
PAINT MONO (-3450 2750);
DISPLAY INVISIBLE (-3450 2750);
FORCEPROP 1 LAST BODY_TYPE PLUMBING
J 0
(-3450 2800);
DISPLAY 0.872340 (-3450 2800);
PAINT GREEN (-3450 2800);
DISPLAY INVISIBLE (-3450 2800);
FORCEPROP 1 LAST HDL_TAP TRUE
J 0
(-3125 2625);
DISPLAY 0.872340 (-3125 2625);
DISPLAY INVISIBLE (-3125 2625);
FORCEPROP 1 LAST PATH I231
J 0
(-3452 2750);
DISPLAY 0.872340 (-3452 2750);
PAINT GREEN (-3452 2750);
DISPLAY INVISIBLE (-3452 2750);
FORCEADD TAP..1
(-3450 2850);
FORCEPROP 3 LASTPIN (-3500 2850) SIG_NAME M_I_CPU1_SB_DQS_DP<4>
J 0
(-3490 2860);
DISPLAY 0.659574 (-3490 2860);
PAINT MONO (-3490 2860);
DISPLAY INVISIBLE (-3490 2860);
FORCEPROP 1 LASTPIN (-3500 2850) BN 4
J 0
(-3512 2858);
DISPLAY 0.489362 (-3512 2858);
PAINT GREEN (-3512 2858);
FORCEPROP 2 LAST CDS_LIB mstr_standard
J 0
(-3450 2850);
DISPLAY 0.723404 (-3450 2850);
PAINT MONO (-3450 2850);
DISPLAY INVISIBLE (-3450 2850);
FORCEPROP 1 LAST BODY_TYPE PLUMBING
J 0
(-3450 2900);
DISPLAY 0.872340 (-3450 2900);
PAINT GREEN (-3450 2900);
DISPLAY INVISIBLE (-3450 2900);
FORCEPROP 1 LAST HDL_TAP TRUE
J 0
(-3125 2725);
DISPLAY 0.872340 (-3125 2725);
DISPLAY INVISIBLE (-3125 2725);
FORCEPROP 1 LAST PATH I232
J 0
(-3452 2850);
DISPLAY 0.872340 (-3452 2850);
PAINT GREEN (-3452 2850);
DISPLAY INVISIBLE (-3452 2850);
FORCEADD TAP..1
(-3450 2650);
FORCEPROP 3 LASTPIN (-3500 2650) SIG_NAME M_I_CPU1_SB_DQS_DP<2>
J 0
(-3490 2660);
DISPLAY 0.659574 (-3490 2660);
PAINT MONO (-3490 2660);
DISPLAY INVISIBLE (-3490 2660);
FORCEPROP 1 LASTPIN (-3500 2650) BN 2
J 0
(-3512 2658);
DISPLAY 0.489362 (-3512 2658);
PAINT GREEN (-3512 2658);
FORCEPROP 2 LAST CDS_LIB mstr_standard
J 0
(-3450 2650);
DISPLAY 0.723404 (-3450 2650);
PAINT MONO (-3450 2650);
DISPLAY INVISIBLE (-3450 2650);
FORCEPROP 1 LAST BODY_TYPE PLUMBING
J 0
(-3450 2700);
DISPLAY 0.872340 (-3450 2700);
PAINT GREEN (-3450 2700);
DISPLAY INVISIBLE (-3450 2700);
FORCEPROP 1 LAST HDL_TAP TRUE
J 0
(-3125 2525);
DISPLAY 0.872340 (-3125 2525);
DISPLAY INVISIBLE (-3125 2525);
FORCEPROP 1 LAST PATH I233
J 0
(-3452 2650);
DISPLAY 0.872340 (-3452 2650);
PAINT GREEN (-3452 2650);
DISPLAY INVISIBLE (-3452 2650);
FORCEADD TAP..1
(-3450 2550);
FORCEPROP 3 LASTPIN (-3500 2550) SIG_NAME M_I_CPU1_SB_DQS_DP<1>
J 0
(-3490 2560);
DISPLAY 0.659574 (-3490 2560);
PAINT MONO (-3490 2560);
DISPLAY INVISIBLE (-3490 2560);
FORCEPROP 1 LASTPIN (-3500 2550) BN 1
J 0
(-3512 2558);
DISPLAY 0.489362 (-3512 2558);
PAINT GREEN (-3512 2558);
FORCEPROP 2 LAST CDS_LIB mstr_standard
J 0
(-3450 2550);
DISPLAY 0.723404 (-3450 2550);
PAINT MONO (-3450 2550);
DISPLAY INVISIBLE (-3450 2550);
FORCEPROP 1 LAST BODY_TYPE PLUMBING
J 0
(-3450 2600);
DISPLAY 0.872340 (-3450 2600);
PAINT GREEN (-3450 2600);
DISPLAY INVISIBLE (-3450 2600);
FORCEPROP 1 LAST HDL_TAP TRUE
J 0
(-3125 2425);
DISPLAY 0.872340 (-3125 2425);
DISPLAY INVISIBLE (-3125 2425);
FORCEPROP 1 LAST PATH I234
J 0
(-3452 2550);
DISPLAY 0.872340 (-3452 2550);
PAINT GREEN (-3452 2550);
DISPLAY INVISIBLE (-3452 2550);
FORCEADD TAP..1
(-3450 2450);
FORCEPROP 3 LASTPIN (-3500 2450) SIG_NAME M_I_CPU1_SB_DQS_DP<0>
J 0
(-3490 2460);
DISPLAY 0.659574 (-3490 2460);
PAINT MONO (-3490 2460);
DISPLAY INVISIBLE (-3490 2460);
FORCEPROP 1 LASTPIN (-3500 2450) BN 0
J 0
(-3512 2458);
DISPLAY 0.489362 (-3512 2458);
PAINT GREEN (-3512 2458);
FORCEPROP 2 LAST CDS_LIB mstr_standard
J 0
(-3450 2450);
DISPLAY 0.723404 (-3450 2450);
PAINT MONO (-3450 2450);
DISPLAY INVISIBLE (-3450 2450);
FORCEPROP 1 LAST BODY_TYPE PLUMBING
J 0
(-3450 2500);
DISPLAY 0.872340 (-3450 2500);
PAINT GREEN (-3450 2500);
DISPLAY INVISIBLE (-3450 2500);
FORCEPROP 1 LAST HDL_TAP TRUE
J 0
(-3125 2325);
DISPLAY 0.872340 (-3125 2325);
DISPLAY INVISIBLE (-3125 2325);
FORCEPROP 1 LAST PATH I235
J 0
(-3452 2450);
DISPLAY 0.872340 (-3452 2450);
PAINT GREEN (-3452 2450);
DISPLAY INVISIBLE (-3452 2450);
FORCEADD SCONN288_DDR506112002KQ..2
(-4400 3400);
FORCEPROP 1 LAST LOCATION J100
J 0
(-5000 4725);
DISPLAY 0.468085 (-5000 4725);
PAINT SKYBLUE (-5000 4725);
FORCEPROP 0 LAST $SEC 2
J 0
(-4850 4875);
DISPLAY 0.680851 (-4850 4875);
PAINT MONO (-4850 4875);
DISPLAY INVISIBLE (-4850 4875);
FORCEPROP 0 LAST CDS_SEC 2
J 0
(-4850 4875);
DISPLAY 1.021277 (-4850 4875);
DISPLAY INVISIBLE (-4850 4875);
FORCEPROP 0 LASTPIN (-3650 3450) $PN 12
J 0
(-3640 3460);
DISPLAY 0.680851 (-3640 3460);
PAINT MONO (-3640 3460);
FORCEPROP 0 LASTPIN (-3650 3500) $PN 11
J 0
(-3640 3510);
DISPLAY 0.680851 (-3640 3510);
PAINT MONO (-3640 3510);
FORCEPROP 0 LASTPIN (-3650 2400) $PN 105
J 0
(-3640 2410);
DISPLAY 0.680851 (-3640 2410);
PAINT MONO (-3640 2410);
FORCEPROP 0 LASTPIN (-3650 2450) $PN 104
J 0
(-3640 2460);
DISPLAY 0.680851 (-3640 2460);
PAINT MONO (-3640 2460);
FORCEPROP 0 LASTPIN (-3650 3550) $PN 23
J 0
(-3640 3560);
DISPLAY 0.680851 (-3640 3560);
PAINT MONO (-3640 3560);
FORCEPROP 0 LASTPIN (-3650 3600) $PN 22
J 0
(-3640 3610);
DISPLAY 0.680851 (-3640 3610);
PAINT MONO (-3640 3610);
FORCEPROP 0 LASTPIN (-3650 2500) $PN 116
J 0
(-3640 2510);
DISPLAY 0.680851 (-3640 2510);
PAINT MONO (-3640 2510);
FORCEPROP 0 LASTPIN (-3650 2550) $PN 115
J 0
(-3640 2560);
DISPLAY 0.680851 (-3640 2560);
PAINT MONO (-3640 2560);
FORCEPROP 0 LASTPIN (-3650 3650) $PN 34
J 0
(-3640 3660);
DISPLAY 0.680851 (-3640 3660);
PAINT MONO (-3640 3660);
FORCEPROP 0 LASTPIN (-3650 3700) $PN 33
J 0
(-3640 3710);
DISPLAY 0.680851 (-3640 3710);
PAINT MONO (-3640 3710);
FORCEPROP 0 LASTPIN (-3650 2600) $PN 127
J 0
(-3640 2610);
DISPLAY 0.680851 (-3640 2610);
PAINT MONO (-3640 2610);
FORCEPROP 0 LASTPIN (-3650 2650) $PN 126
J 0
(-3640 2660);
DISPLAY 0.680851 (-3640 2660);
PAINT MONO (-3640 2660);
FORCEPROP 0 LASTPIN (-3650 3750) $PN 45
J 0
(-3640 3760);
DISPLAY 0.680851 (-3640 3760);
PAINT MONO (-3640 3760);
FORCEPROP 0 LASTPIN (-3650 3800) $PN 44
J 0
(-3640 3810);
DISPLAY 0.680851 (-3640 3810);
PAINT MONO (-3640 3810);
FORCEPROP 0 LASTPIN (-3650 2700) $PN 138
J 0
(-3640 2710);
DISPLAY 0.680851 (-3640 2710);
PAINT MONO (-3640 2710);
FORCEPROP 0 LASTPIN (-3650 2750) $PN 137
J 0
(-3640 2760);
DISPLAY 0.680851 (-3640 2760);
PAINT MONO (-3640 2760);
FORCEPROP 0 LASTPIN (-3650 3850) $PN 56
J 0
(-3640 3860);
DISPLAY 0.680851 (-3640 3860);
PAINT MONO (-3640 3860);
FORCEPROP 0 LASTPIN (-3650 3900) $PN 55
J 0
(-3640 3910);
DISPLAY 0.680851 (-3640 3910);
PAINT MONO (-3640 3910);
FORCEPROP 0 LASTPIN (-3650 2800) $PN 238
J 0
(-3640 2810);
DISPLAY 0.680851 (-3640 2810);
PAINT MONO (-3640 2810);
FORCEPROP 0 LASTPIN (-3650 2850) $PN 239
J 0
(-3640 2860);
DISPLAY 0.680851 (-3640 2860);
PAINT MONO (-3640 2860);
FORCEPROP 0 LASTPIN (-3650 3950) $PN 156
J 0
(-3640 3960);
DISPLAY 0.680851 (-3640 3960);
PAINT MONO (-3640 3960);
FORCEPROP 0 LASTPIN (-3650 4000) $PN 157
J 0
(-3640 4010);
DISPLAY 0.680851 (-3640 4010);
PAINT MONO (-3640 4010);
FORCEPROP 0 LASTPIN (-3650 2900) $PN 249
J 0
(-3640 2910);
DISPLAY 0.680851 (-3640 2910);
PAINT MONO (-3640 2910);
FORCEPROP 0 LASTPIN (-3650 2950) $PN 250
J 0
(-3640 2960);
DISPLAY 0.680851 (-3640 2960);
PAINT MONO (-3640 2960);
FORCEPROP 0 LASTPIN (-3650 4050) $PN 167
J 0
(-3640 4060);
DISPLAY 0.680851 (-3640 4060);
PAINT MONO (-3640 4060);
FORCEPROP 0 LASTPIN (-3650 4100) $PN 168
J 0
(-3640 4110);
DISPLAY 0.680851 (-3640 4110);
PAINT MONO (-3640 4110);
FORCEPROP 0 LASTPIN (-3650 3000) $PN 260
J 0
(-3640 3010);
DISPLAY 0.680851 (-3640 3010);
PAINT MONO (-3640 3010);
FORCEPROP 0 LASTPIN (-3650 3050) $PN 261
J 0
(-3640 3060);
DISPLAY 0.680851 (-3640 3060);
PAINT MONO (-3640 3060);
FORCEPROP 0 LASTPIN (-3650 4150) $PN 178
J 0
(-3640 4160);
DISPLAY 0.680851 (-3640 4160);
PAINT MONO (-3640 4160);
FORCEPROP 0 LASTPIN (-3650 4200) $PN 179
J 0
(-3640 4210);
DISPLAY 0.680851 (-3640 4210);
PAINT MONO (-3640 4210);
FORCEPROP 0 LASTPIN (-3650 3100) $PN 271
J 0
(-3640 3110);
DISPLAY 0.680851 (-3640 3110);
PAINT MONO (-3640 3110);
FORCEPROP 0 LASTPIN (-3650 3150) $PN 272
J 0
(-3640 3160);
DISPLAY 0.680851 (-3640 3160);
PAINT MONO (-3640 3160);
FORCEPROP 0 LASTPIN (-3650 4250) $PN 189
J 0
(-3640 4260);
DISPLAY 0.680851 (-3640 4260);
PAINT MONO (-3640 4260);
FORCEPROP 0 LASTPIN (-3650 4300) $PN 190
J 0
(-3640 4310);
DISPLAY 0.680851 (-3640 4310);
PAINT MONO (-3640 4310);
FORCEPROP 0 LASTPIN (-3650 3200) $PN 282
J 0
(-3640 3210);
DISPLAY 0.680851 (-3640 3210);
PAINT MONO (-3640 3210);
FORCEPROP 0 LASTPIN (-3650 3250) $PN 283
J 0
(-3640 3260);
DISPLAY 0.680851 (-3640 3260);
PAINT MONO (-3640 3260);
FORCEPROP 0 LASTPIN (-3650 4350) $PN 200
J 0
(-3640 4360);
DISPLAY 0.680851 (-3640 4360);
PAINT MONO (-3640 4360);
FORCEPROP 0 LASTPIN (-3650 4400) $PN 201
J 0
(-3640 4410);
DISPLAY 0.680851 (-3640 4410);
PAINT MONO (-3640 4410);
FORCEPROP 0 LASTPIN (-3650 3300) $PN 94
J 0
(-3640 3310);
DISPLAY 0.680851 (-3640 3310);
PAINT MONO (-3640 3310);
FORCEPROP 0 LASTPIN (-3650 3350) $PN 93
J 0
(-3640 3360);
DISPLAY 0.680851 (-3640 3360);
PAINT MONO (-3640 3360);
FORCEPROP 1 LAST MATERIAL IO
J 0
(-5000 4575);
DISPLAY 0.468085 (-5000 4575);
PAINT SKYBLUE (-5000 4575);
FORCEPROP 2 LAST VALUE SCONN288_DDR506112002KQ
J 0
(-4850 4775);
DISPLAY 0.489362 (-4850 4775);
PAINT SKYBLUE (-4850 4775);
FORCEPROP 2 LAST PART_TYPE SMLF
J 0
(-4850 4825);
DISPLAY 1.021277 (-4850 4825);
FORCEPROP 1 LAST PART_NUMBER DFHST8FS479
J 0
(-5000 4650);
DISPLAY 0.468085 (-5000 4650);
PAINT SKYBLUE (-5000 4650);
FORCEPROP 1 LAST CDS_LMAN_SYM_OUTLINE -600,1150,600,-1150
J 0
(-4400 3400);
DISPLAY 0.468085 (-4400 3400);
PAINT GREEN (-4400 3400);
DISPLAY INVISIBLE (-4400 3400);
FORCEPROP 1 LAST PATH I236
J 0
(-4400 3400);
DISPLAY 0.723404 (-4400 3400);
PAINT GREEN (-4400 3400);
DISPLAY INVISIBLE (-4400 3400);
FORCEPROP 1 LAST NEEDS_NO_SIZE TRUE
J 0
(-4400 3400);
DISPLAY 0.723404 (-4400 3400);
PAINT GREEN (-4400 3400);
DISPLAY INVISIBLE (-4400 3400);
FORCEPROP 2 LAST CDS_LIB pure_quanta
J 0
(-4400 3400);
DISPLAY INVISIBLE (-4400 3400);
FORCEADD GND..1
(-2825 5450);
FORCEPROP 3 LASTPIN (-2825 5500) SIG_NAME GND\g
J 0
(-2815 5510);
DISPLAY 0.659574 (-2815 5510);
PAINT MONO (-2815 5510);
DISPLAY INVISIBLE (-2815 5510);
FORCEPROP 2 LAST CDS_LIB pure_quanta_power
J 0
(-2825 5450);
DISPLAY INVISIBLE (-2825 5450);
FORCEPROP 2 LAST BOM_COST MEM
J 0
(-2800 5575);
DISPLAY 0.659574 (-2800 5575);
DISPLAY INVISIBLE (-2800 5575);
FORCEPROP 1 LAST SIZE 1B
J 0
(-2750 5400);
DISPLAY 0.723404 (-2750 5400);
PAINT GREEN (-2750 5400);
DISPLAY INVISIBLE (-2750 5400);
FORCEPROP 1 LAST PATH I237
J 0
(-2750 5450);
DISPLAY 0.872340 (-2750 5450);
PAINT AQUA (-2750 5450);
DISPLAY INVISIBLE (-2750 5450);
FORCEPROP 2 LAST ROOM MEM_EFGH_DECOUPLING_CAPS
J 0
(-2800 5525);
DISPLAY 0.659574 (-2800 5525);
PAINT RED (-2800 5525);
DISPLAY INVISIBLE (-2800 5525);
FORCEPROP 1 LAST HDL_POWER GND
J 0
(-2825 5600);
DISPLAY 0.723404 (-2825 5600);
PAINT GREEN (-2825 5600);
DISPLAY INVISIBLE (-2825 5600);
FORCEADD Q_CAP..1
R 2
(-2825 5800);
FORCEPROP 1 LAST LOCATION C534
J 2
(-2875 5900);
DISPLAY 0.489362 (-2875 5900);
PAINT SKYBLUE (-2875 5900);
FORCEPROP 0 LAST $SEC 1
J 0
(-2875 5950);
DISPLAY 0.680851 (-2875 5950);
PAINT MONO (-2875 5950);
DISPLAY INVISIBLE (-2875 5950);
FORCEPROP 0 LAST CDS_SEC 1
J 0
(-2875 5950);
DISPLAY 0.680851 (-2875 5950);
DISPLAY INVISIBLE (-2875 5950);
FORCEPROP 1 LASTPIN (-2825 5900) $PN 1
J 2
(-2835 5880);
DISPLAY 0.489362 (-2835 5880);
PAINT MONO (-2835 5880);
FORCEPROP 1 LASTPIN (-2825 5700) $PN 2
J 2
(-2835 5680);
DISPLAY 0.489362 (-2835 5680);
PAINT MONO (-2835 5680);
FORCEPROP 1 LAST MATERIAL X6S
J 2
(-2875 5700);
DISPLAY 0.489362 (-2875 5700);
PAINT SKYBLUE (-2875 5700);
FORCEPROP 1 LAST TOLERANCE 10%
J 2
(-2875 5750);
DISPLAY 0.489362 (-2875 5750);
PAINT SKYBLUE (-2875 5750);
FORCEPROP 1 LAST PART_NUMBER CH6104KEA00
J 2
(-2875 5650);
DISPLAY 0.489362 (-2875 5650);
PAINT SKYBLUE (-2875 5650);
FORCEPROP 1 LAST VOLTAGE 25V
J 2
(-2875 5800);
DISPLAY 0.489362 (-2875 5800);
PAINT SKYBLUE (-2875 5800);
FORCEPROP 1 LAST PACK_TYPE C0805
J 2
(-2875 5600);
DISPLAY 0.489362 (-2875 5600);
PAINT SKYBLUE (-2875 5600);
FORCEPROP 1 LAST VALUE 10UF
J 2
(-2875 5850);
DISPLAY 0.489362 (-2875 5850);
PAINT SKYBLUE (-2875 5850);
FORCEPROP 0 LAST BOM_COST MEM
J 2
(-2880 5945);
DISPLAY 0.595745 (-2880 5945);
PAINT MONO (-2880 5945);
DISPLAY INVISIBLE (-2880 5945);
FORCEPROP 2 LAST CDS_LIB pure_quanta
J 0
(-2825 5800);
DISPLAY INVISIBLE (-2825 5800);
FORCEPROP 1 LAST PATH I238
J 2
(-2875 5950);
DISPLAY 0.978723 (-2875 5950);
PAINT WHITE (-2875 5950);
DISPLAY INVISIBLE (-2875 5950);
FORCEPROP 0 LAST ROOM MEM_CH_A_CPU0_DIMM1
J 2
(-2880 5945);
DISPLAY 0.595745 (-2880 5945);
PAINT RED (-2880 5945);
DISPLAY INVISIBLE (-2880 5945);
FORCEADD Q_CAP..1
R 2
(-2250 5800);
FORCEPROP 1 LAST LOCATION C535
J 2
(-2300 5900);
DISPLAY 0.489362 (-2300 5900);
PAINT SKYBLUE (-2300 5900);
FORCEPROP 0 LAST $SEC 1
J 0
(-2300 5950);
DISPLAY 0.680851 (-2300 5950);
PAINT MONO (-2300 5950);
DISPLAY INVISIBLE (-2300 5950);
FORCEPROP 0 LAST CDS_SEC 1
J 0
(-2300 5950);
DISPLAY 0.680851 (-2300 5950);
DISPLAY INVISIBLE (-2300 5950);
FORCEPROP 1 LASTPIN (-2250 5900) $PN 1
J 2
(-2260 5880);
DISPLAY 0.489362 (-2260 5880);
PAINT MONO (-2260 5880);
FORCEPROP 1 LASTPIN (-2250 5700) $PN 2
J 2
(-2260 5680);
DISPLAY 0.489362 (-2260 5680);
PAINT MONO (-2260 5680);
FORCEPROP 1 LAST MATERIAL X6S
J 2
(-2300 5700);
DISPLAY 0.489362 (-2300 5700);
PAINT SKYBLUE (-2300 5700);
FORCEPROP 1 LAST TOLERANCE 10%
J 2
(-2300 5750);
DISPLAY 0.489362 (-2300 5750);
PAINT SKYBLUE (-2300 5750);
FORCEPROP 1 LAST VALUE 10UF
J 2
(-2300 5850);
DISPLAY 0.489362 (-2300 5850);
PAINT SKYBLUE (-2300 5850);
FORCEPROP 1 LAST PART_NUMBER CH6104KEA00
J 2
(-2300 5650);
DISPLAY 0.489362 (-2300 5650);
PAINT SKYBLUE (-2300 5650);
FORCEPROP 1 LAST VOLTAGE 25V
J 2
(-2300 5800);
DISPLAY 0.489362 (-2300 5800);
PAINT SKYBLUE (-2300 5800);
FORCEPROP 1 LAST PACK_TYPE C0805
J 2
(-2300 5600);
DISPLAY 0.489362 (-2300 5600);
PAINT SKYBLUE (-2300 5600);
FORCEPROP 0 LAST BOM_COST MEM
J 2
(-2305 5945);
DISPLAY 0.595745 (-2305 5945);
PAINT MONO (-2305 5945);
DISPLAY INVISIBLE (-2305 5945);
FORCEPROP 2 LAST CDS_LIB pure_quanta
J 0
(-2250 5800);
DISPLAY INVISIBLE (-2250 5800);
FORCEPROP 1 LAST PATH I239
J 2
(-2300 5950);
DISPLAY 0.978723 (-2300 5950);
PAINT WHITE (-2300 5950);
DISPLAY INVISIBLE (-2300 5950);
FORCEPROP 0 LAST ROOM MEM_CH_A_CPU0_DIMM1
J 2
(-2305 5945);
DISPLAY 0.595745 (-2305 5945);
PAINT RED (-2305 5945);
DISPLAY INVISIBLE (-2305 5945);
FORCEADD TAP..1
R 2
(-7675 3200);
FORCEPROP 3 LASTPIN (-7625 3200) SIG_NAME M_I_CPU1_SB_CB<1>
J 0
(-7615 3210);
DISPLAY 0.659574 (-7615 3210);
PAINT MONO (-7615 3210);
DISPLAY INVISIBLE (-7615 3210);
FORCEPROP 1 LASTPIN (-7625 3200) BN 1
J 2
(-7613 3208);
DISPLAY 0.489362 (-7613 3208);
PAINT GREEN (-7613 3208);
FORCEPROP 2 LAST CDS_LIB mstr_standard
J 0
(-7675 3200);
DISPLAY 0.723404 (-7675 3200);
PAINT MONO (-7675 3200);
DISPLAY INVISIBLE (-7675 3200);
FORCEPROP 1 LAST BODY_TYPE PLUMBING
J 2
(-7675 3250);
DISPLAY 0.872340 (-7675 3250);
PAINT GREEN (-7675 3250);
DISPLAY INVISIBLE (-7675 3250);
FORCEPROP 1 LAST HDL_TAP TRUE
J 2
(-8000 3075);
DISPLAY 0.872340 (-8000 3075);
DISPLAY INVISIBLE (-8000 3075);
FORCEPROP 1 LAST PATH I24
J 2
(-7673 3200);
DISPLAY 0.872340 (-7673 3200);
PAINT GREEN (-7673 3200);
DISPLAY INVISIBLE (-7673 3200);
FORCEADD UNIVERSAL_POWER..1
(-2825 6125);
FORCEPROP 3 LASTPIN (-2825 6075) SIG_NAME P12V_MEM_1\g
J 0
(-2815 6085);
DISPLAY 0.659574 (-2815 6085);
PAINT MONO (-2815 6085);
DISPLAY INVISIBLE (-2815 6085);
FORCEPROP 1 LAST HDL_POWER P12V_MEM_1
J 1
(-2825 6175);
DISPLAY 0.489362 (-2825 6175);
PAINT GREEN (-2825 6175);
FORCEPROP 2 LAST CDS_LIB pure_quanta_power
J 0
(-2825 6125);
DISPLAY INVISIBLE (-2825 6125);
FORCEPROP 1 LAST PATH I240
J 0
(-2775 6150);
DISPLAY 0.872340 (-2775 6150);
PAINT AQUA (-2775 6150);
DISPLAY INVISIBLE (-2775 6150);
FORCEADD OFFPAGE..1
(-8275 2625);
FORCEPROP 2 LAST $XR5 108 
J 0
(-9157 2625);
DISPLAY 0.638298 (-9157 2625);
PAINT MONO (-9157 2625);
FORCEPROP 2 LAST $XR4 107 
J 0
(-9037 2625);
DISPLAY 0.638298 (-9037 2625);
PAINT MONO (-9037 2625);
FORCEPROP 2 LAST $XR3 106 
J 0
(-8917 2625);
DISPLAY 0.638298 (-8917 2625);
PAINT MONO (-8917 2625);
FORCEPROP 2 LAST $XR2 104 
J 0
(-8797 2625);
DISPLAY 0.638298 (-8797 2625);
PAINT MONO (-8797 2625);
FORCEPROP 2 LAST $XR1 103 
J 0
(-8677 2625);
DISPLAY 0.638298 (-8677 2625);
PAINT MONO (-8677 2625);
FORCEPROP 2 LAST $XR0 136 
J 0
(-8557 2625);
DISPLAY 0.638298 (-8557 2625);
PAINT MONO (-8557 2625);
FORCEPROP 2 LAST PATH I241
J 0
(-8550 2675);
DISPLAY 0.680851 (-8550 2675);
DISPLAY INVISIBLE (-8550 2675);
FORCEPROP 1 LAST COMMENT_BODY TRUE
J 0
(-8150 2525);
DISPLAY 0.872340 (-8150 2525);
PAINT GREEN (-8150 2525);
DISPLAY INVISIBLE (-8150 2525);
FORCEPROP 1 LAST OFFPAGE TRUE
J 0
(-7950 2500);
DISPLAY 0.872340 (-7950 2500);
PAINT GREEN (-7950 2500);
DISPLAY INVISIBLE (-7950 2500);
FORCEPROP 2 LAST CDS_LIB mstr_standard
J 0
(-8275 2625);
DISPLAY 0.808511 (-8275 2625);
DISPLAY INVISIBLE (-8275 2625);
FORCEADD Q_RES..1
(-7725 2625);
FORCEPROP 1 LAST $LOCATION R1588
J 0
(-7775 2650);
DISPLAY 0.510638 (-7775 2650);
PAINT SKYBLUE (-7775 2650);
FORCEPROP 0 LAST CDS_LOCATION R1588
J 0
(-7775 2725);
DISPLAY 0.680851 (-7775 2725);
DISPLAY INVISIBLE (-7775 2725);
FORCEPROP 0 LAST $SEC 1
J 0
(-7775 2725);
DISPLAY 0.680851 (-7775 2725);
PAINT MONO (-7775 2725);
DISPLAY INVISIBLE (-7775 2725);
FORCEPROP 0 LAST CDS_SEC 1
J 0
(-7775 2725);
DISPLAY 0.680851 (-7775 2725);
DISPLAY INVISIBLE (-7775 2725);
FORCEPROP 1 LASTPIN (-7825 2625) $PN 1
J 0
(-7813 2637);
DISPLAY 0.787234 (-7813 2637);
PAINT MONO (-7813 2637);
FORCEPROP 1 LASTPIN (-7625 2625) $PN 2
J 0
(-7663 2637);
DISPLAY 0.787234 (-7663 2637);
PAINT MONO (-7663 2637);
FORCEPROP 1 LAST VALUE 49.9
J 2
(-7575 2675);
DISPLAY 0.510638 (-7575 2675);
PAINT SKYBLUE (-7575 2675);
FORCEPROP 2 LAST CDS_LIB pure_quanta
J 0
(-7725 2625);
DISPLAY INVISIBLE (-7725 2625);
FORCEPROP 1 LAST PATH I242
J 0
(-7775 2775);
DISPLAY 0.978723 (-7775 2775);
PAINT WHITE (-7775 2775);
DISPLAY INVISIBLE (-7775 2775);
FORCEPROP 1 LAST PART_NUMBER CS04992FB07
J 0
(-7775 2725);
DISPLAY 0.978723 (-7775 2725);
DISPLAY INVISIBLE (-7775 2725);
FORCEPROP 1 LAST TOLERANCE 1%
J 0
(-7725 2525);
DISPLAY 0.978723 (-7725 2525);
DISPLAY INVISIBLE (-7725 2525);
FORCEPROP 1 LAST WATTAGE 1/16W
J 2
(-7750 2475);
DISPLAY 0.978723 (-7750 2475);
DISPLAY INVISIBLE (-7750 2475);
FORCEPROP 1 LAST PACK_TYPE 0402LF
J 0
(-7475 2475);
DISPLAY 0.978723 (-7475 2475);
DISPLAY INVISIBLE (-7475 2475);
FORCEPROP 1 LAST MATERIAL CHIP
J 0
(-7725 2475);
DISPLAY 0.978723 (-7725 2475);
DISPLAY INVISIBLE (-7725 2475);
FORCEADD TAP..1
R 2
(-7675 3250);
FORCEPROP 3 LASTPIN (-7625 3250) SIG_NAME M_I_CPU1_SB_CB<2>
J 0
(-7615 3260);
DISPLAY 0.659574 (-7615 3260);
PAINT MONO (-7615 3260);
DISPLAY INVISIBLE (-7615 3260);
FORCEPROP 1 LASTPIN (-7625 3250) BN 2
J 2
(-7613 3258);
DISPLAY 0.489362 (-7613 3258);
PAINT GREEN (-7613 3258);
FORCEPROP 2 LAST CDS_LIB mstr_standard
J 0
(-7675 3250);
DISPLAY 0.723404 (-7675 3250);
PAINT MONO (-7675 3250);
DISPLAY INVISIBLE (-7675 3250);
FORCEPROP 1 LAST BODY_TYPE PLUMBING
J 2
(-7675 3300);
DISPLAY 0.872340 (-7675 3300);
PAINT GREEN (-7675 3300);
DISPLAY INVISIBLE (-7675 3300);
FORCEPROP 1 LAST HDL_TAP TRUE
J 2
(-8000 3125);
DISPLAY 0.872340 (-8000 3125);
DISPLAY INVISIBLE (-8000 3125);
FORCEPROP 1 LAST PATH I25
J 2
(-7673 3250);
DISPLAY 0.872340 (-7673 3250);
PAINT GREEN (-7673 3250);
DISPLAY INVISIBLE (-7673 3250);
FORCEADD TAP..1
R 2
(-7675 3300);
FORCEPROP 3 LASTPIN (-7625 3300) SIG_NAME M_I_CPU1_SB_CB<3>
J 0
(-7615 3310);
DISPLAY 0.659574 (-7615 3310);
PAINT MONO (-7615 3310);
DISPLAY INVISIBLE (-7615 3310);
FORCEPROP 1 LASTPIN (-7625 3300) BN 3
J 2
(-7613 3308);
DISPLAY 0.489362 (-7613 3308);
PAINT GREEN (-7613 3308);
FORCEPROP 2 LAST CDS_LIB mstr_standard
J 0
(-7675 3300);
DISPLAY 0.723404 (-7675 3300);
PAINT MONO (-7675 3300);
DISPLAY INVISIBLE (-7675 3300);
FORCEPROP 1 LAST BODY_TYPE PLUMBING
J 2
(-7675 3350);
DISPLAY 0.872340 (-7675 3350);
PAINT GREEN (-7675 3350);
DISPLAY INVISIBLE (-7675 3350);
FORCEPROP 1 LAST HDL_TAP TRUE
J 2
(-8000 3175);
DISPLAY 0.872340 (-8000 3175);
DISPLAY INVISIBLE (-8000 3175);
FORCEPROP 1 LAST PATH I26
J 2
(-7673 3300);
DISPLAY 0.872340 (-7673 3300);
PAINT GREEN (-7673 3300);
DISPLAY INVISIBLE (-7673 3300);
FORCEADD TAP..1
R 2
(-7675 3350);
FORCEPROP 3 LASTPIN (-7625 3350) SIG_NAME M_I_CPU1_SB_CB<4>
J 0
(-7615 3360);
DISPLAY 0.659574 (-7615 3360);
PAINT MONO (-7615 3360);
DISPLAY INVISIBLE (-7615 3360);
FORCEPROP 1 LASTPIN (-7625 3350) BN 4
J 2
(-7613 3358);
DISPLAY 0.489362 (-7613 3358);
PAINT GREEN (-7613 3358);
FORCEPROP 2 LAST CDS_LIB mstr_standard
J 0
(-7675 3350);
DISPLAY 0.723404 (-7675 3350);
PAINT MONO (-7675 3350);
DISPLAY INVISIBLE (-7675 3350);
FORCEPROP 1 LAST BODY_TYPE PLUMBING
J 2
(-7675 3400);
DISPLAY 0.872340 (-7675 3400);
PAINT GREEN (-7675 3400);
DISPLAY INVISIBLE (-7675 3400);
FORCEPROP 1 LAST HDL_TAP TRUE
J 2
(-8000 3225);
DISPLAY 0.872340 (-8000 3225);
DISPLAY INVISIBLE (-8000 3225);
FORCEPROP 1 LAST PATH I27
J 2
(-7673 3350);
DISPLAY 0.872340 (-7673 3350);
PAINT GREEN (-7673 3350);
DISPLAY INVISIBLE (-7673 3350);
FORCEADD TAP..1
R 2
(-7675 3400);
FORCEPROP 3 LASTPIN (-7625 3400) SIG_NAME M_I_CPU1_SB_CB<5>
J 0
(-7615 3410);
DISPLAY 0.659574 (-7615 3410);
PAINT MONO (-7615 3410);
DISPLAY INVISIBLE (-7615 3410);
FORCEPROP 1 LASTPIN (-7625 3400) BN 5
J 2
(-7613 3408);
DISPLAY 0.489362 (-7613 3408);
PAINT GREEN (-7613 3408);
FORCEPROP 2 LAST CDS_LIB mstr_standard
J 0
(-7675 3400);
DISPLAY 0.723404 (-7675 3400);
PAINT MONO (-7675 3400);
DISPLAY INVISIBLE (-7675 3400);
FORCEPROP 1 LAST BODY_TYPE PLUMBING
J 2
(-7675 3450);
DISPLAY 0.872340 (-7675 3450);
PAINT GREEN (-7675 3450);
DISPLAY INVISIBLE (-7675 3450);
FORCEPROP 1 LAST HDL_TAP TRUE
J 2
(-8000 3275);
DISPLAY 0.872340 (-8000 3275);
DISPLAY INVISIBLE (-8000 3275);
FORCEPROP 1 LAST PATH I28
J 2
(-7673 3400);
DISPLAY 0.872340 (-7673 3400);
PAINT GREEN (-7673 3400);
DISPLAY INVISIBLE (-7673 3400);
FORCEADD TAP..1
R 2
(-7675 3450);
FORCEPROP 3 LASTPIN (-7625 3450) SIG_NAME M_I_CPU1_SB_CB<6>
J 0
(-7615 3460);
DISPLAY 0.659574 (-7615 3460);
PAINT MONO (-7615 3460);
DISPLAY INVISIBLE (-7615 3460);
FORCEPROP 1 LASTPIN (-7625 3450) BN 6
J 2
(-7613 3458);
DISPLAY 0.489362 (-7613 3458);
PAINT GREEN (-7613 3458);
FORCEPROP 2 LAST CDS_LIB mstr_standard
J 0
(-7675 3450);
DISPLAY 0.723404 (-7675 3450);
PAINT MONO (-7675 3450);
DISPLAY INVISIBLE (-7675 3450);
FORCEPROP 1 LAST BODY_TYPE PLUMBING
J 2
(-7675 3500);
DISPLAY 0.872340 (-7675 3500);
PAINT GREEN (-7675 3500);
DISPLAY INVISIBLE (-7675 3500);
FORCEPROP 1 LAST HDL_TAP TRUE
J 2
(-8000 3325);
DISPLAY 0.872340 (-8000 3325);
DISPLAY INVISIBLE (-8000 3325);
FORCEPROP 1 LAST PATH I29
J 2
(-7673 3450);
DISPLAY 0.872340 (-7673 3450);
PAINT GREEN (-7673 3450);
DISPLAY INVISIBLE (-7673 3450);
FORCEADD TAP..1
R 2
(-7675 3500);
FORCEPROP 3 LASTPIN (-7625 3500) SIG_NAME M_I_CPU1_SB_CB<7>
J 0
(-7615 3510);
DISPLAY 0.659574 (-7615 3510);
PAINT MONO (-7615 3510);
DISPLAY INVISIBLE (-7615 3510);
FORCEPROP 1 LASTPIN (-7625 3500) BN 7
J 2
(-7613 3508);
DISPLAY 0.489362 (-7613 3508);
PAINT GREEN (-7613 3508);
FORCEPROP 2 LAST CDS_LIB mstr_standard
J 0
(-7675 3500);
DISPLAY 0.723404 (-7675 3500);
PAINT MONO (-7675 3500);
DISPLAY INVISIBLE (-7675 3500);
FORCEPROP 1 LAST BODY_TYPE PLUMBING
J 2
(-7675 3550);
DISPLAY 0.872340 (-7675 3550);
PAINT GREEN (-7675 3550);
DISPLAY INVISIBLE (-7675 3550);
FORCEPROP 1 LAST HDL_TAP TRUE
J 2
(-8000 3375);
DISPLAY 0.872340 (-8000 3375);
DISPLAY INVISIBLE (-8000 3375);
FORCEPROP 1 LAST PATH I30
J 2
(-7673 3500);
DISPLAY 0.872340 (-7673 3500);
PAINT GREEN (-7673 3500);
DISPLAY INVISIBLE (-7673 3500);
FORCEADD TAP..1
R 2
(-7675 3600);
FORCEPROP 3 LASTPIN (-7625 3600) SIG_NAME M_I_CPU1_SA_CB<0>
J 0
(-7615 3610);
DISPLAY 0.659574 (-7615 3610);
PAINT MONO (-7615 3610);
DISPLAY INVISIBLE (-7615 3610);
FORCEPROP 1 LASTPIN (-7625 3600) BN 0
J 2
(-7613 3608);
DISPLAY 0.489362 (-7613 3608);
PAINT GREEN (-7613 3608);
FORCEPROP 2 LAST CDS_LIB mstr_standard
J 0
(-7675 3600);
DISPLAY 0.723404 (-7675 3600);
PAINT MONO (-7675 3600);
DISPLAY INVISIBLE (-7675 3600);
FORCEPROP 1 LAST BODY_TYPE PLUMBING
J 2
(-7675 3650);
DISPLAY 0.872340 (-7675 3650);
PAINT GREEN (-7675 3650);
DISPLAY INVISIBLE (-7675 3650);
FORCEPROP 1 LAST HDL_TAP TRUE
J 2
(-8000 3475);
DISPLAY 0.872340 (-8000 3475);
DISPLAY INVISIBLE (-8000 3475);
FORCEPROP 1 LAST PATH I31
J 2
(-7673 3600);
DISPLAY 0.872340 (-7673 3600);
PAINT GREEN (-7673 3600);
DISPLAY INVISIBLE (-7673 3600);
FORCEADD TAP..1
R 2
(-7675 3650);
FORCEPROP 3 LASTPIN (-7625 3650) SIG_NAME M_I_CPU1_SA_CB<1>
J 0
(-7615 3660);
DISPLAY 0.659574 (-7615 3660);
PAINT MONO (-7615 3660);
DISPLAY INVISIBLE (-7615 3660);
FORCEPROP 1 LASTPIN (-7625 3650) BN 1
J 2
(-7613 3658);
DISPLAY 0.489362 (-7613 3658);
PAINT GREEN (-7613 3658);
FORCEPROP 2 LAST CDS_LIB mstr_standard
J 0
(-7675 3650);
DISPLAY 0.723404 (-7675 3650);
PAINT MONO (-7675 3650);
DISPLAY INVISIBLE (-7675 3650);
FORCEPROP 1 LAST BODY_TYPE PLUMBING
J 2
(-7675 3700);
DISPLAY 0.872340 (-7675 3700);
PAINT GREEN (-7675 3700);
DISPLAY INVISIBLE (-7675 3700);
FORCEPROP 1 LAST HDL_TAP TRUE
J 2
(-8000 3525);
DISPLAY 0.872340 (-8000 3525);
DISPLAY INVISIBLE (-8000 3525);
FORCEPROP 1 LAST PATH I32
J 2
(-7673 3650);
DISPLAY 0.872340 (-7673 3650);
PAINT GREEN (-7673 3650);
DISPLAY INVISIBLE (-7673 3650);
FORCEADD TAP..1
R 2
(-7675 3750);
FORCEPROP 3 LASTPIN (-7625 3750) SIG_NAME M_I_CPU1_SA_CB<3>
J 0
(-7615 3760);
DISPLAY 0.659574 (-7615 3760);
PAINT MONO (-7615 3760);
DISPLAY INVISIBLE (-7615 3760);
FORCEPROP 1 LASTPIN (-7625 3750) BN 3
J 2
(-7613 3758);
DISPLAY 0.489362 (-7613 3758);
PAINT GREEN (-7613 3758);
FORCEPROP 2 LAST CDS_LIB mstr_standard
J 0
(-7675 3750);
DISPLAY 0.723404 (-7675 3750);
PAINT MONO (-7675 3750);
DISPLAY INVISIBLE (-7675 3750);
FORCEPROP 1 LAST BODY_TYPE PLUMBING
J 2
(-7675 3800);
DISPLAY 0.872340 (-7675 3800);
PAINT GREEN (-7675 3800);
DISPLAY INVISIBLE (-7675 3800);
FORCEPROP 1 LAST HDL_TAP TRUE
J 2
(-8000 3625);
DISPLAY 0.872340 (-8000 3625);
DISPLAY INVISIBLE (-8000 3625);
FORCEPROP 1 LAST PATH I33
J 2
(-7673 3750);
DISPLAY 0.872340 (-7673 3750);
PAINT GREEN (-7673 3750);
DISPLAY INVISIBLE (-7673 3750);
FORCEADD TAP..1
R 2
(-7675 3700);
FORCEPROP 3 LASTPIN (-7625 3700) SIG_NAME M_I_CPU1_SA_CB<2>
J 0
(-7615 3710);
DISPLAY 0.659574 (-7615 3710);
PAINT MONO (-7615 3710);
DISPLAY INVISIBLE (-7615 3710);
FORCEPROP 1 LASTPIN (-7625 3700) BN 2
J 2
(-7613 3708);
DISPLAY 0.489362 (-7613 3708);
PAINT GREEN (-7613 3708);
FORCEPROP 2 LAST CDS_LIB mstr_standard
J 0
(-7675 3700);
DISPLAY 0.723404 (-7675 3700);
PAINT MONO (-7675 3700);
DISPLAY INVISIBLE (-7675 3700);
FORCEPROP 1 LAST BODY_TYPE PLUMBING
J 2
(-7675 3750);
DISPLAY 0.872340 (-7675 3750);
PAINT GREEN (-7675 3750);
DISPLAY INVISIBLE (-7675 3750);
FORCEPROP 1 LAST HDL_TAP TRUE
J 2
(-8000 3575);
DISPLAY 0.872340 (-8000 3575);
DISPLAY INVISIBLE (-8000 3575);
FORCEPROP 1 LAST PATH I34
J 2
(-7673 3700);
DISPLAY 0.872340 (-7673 3700);
PAINT GREEN (-7673 3700);
DISPLAY INVISIBLE (-7673 3700);
FORCEADD TAP..1
(-5975 2150);
FORCEPROP 3 LASTPIN (-6025 2150) SIG_NAME M_I_CPU1_SB_DQ<0>
J 0
(-6015 2160);
DISPLAY 0.659574 (-6015 2160);
PAINT MONO (-6015 2160);
DISPLAY INVISIBLE (-6015 2160);
FORCEPROP 1 LASTPIN (-6025 2150) BN 0
J 0
(-6037 2158);
DISPLAY 0.489362 (-6037 2158);
PAINT GREEN (-6037 2158);
FORCEPROP 2 LAST CDS_LIB mstr_standard
J 0
(-5975 2150);
DISPLAY 0.723404 (-5975 2150);
PAINT MONO (-5975 2150);
DISPLAY INVISIBLE (-5975 2150);
FORCEPROP 1 LAST BODY_TYPE PLUMBING
J 0
(-5975 2200);
DISPLAY 0.872340 (-5975 2200);
PAINT GREEN (-5975 2200);
DISPLAY INVISIBLE (-5975 2200);
FORCEPROP 1 LAST HDL_TAP TRUE
J 0
(-5650 2025);
DISPLAY 0.872340 (-5650 2025);
DISPLAY INVISIBLE (-5650 2025);
FORCEPROP 1 LAST PATH I35
J 0
(-5977 2150);
DISPLAY 0.872340 (-5977 2150);
PAINT GREEN (-5977 2150);
DISPLAY INVISIBLE (-5977 2150);
FORCEADD TAP..1
(-5975 2250);
FORCEPROP 3 LASTPIN (-6025 2250) SIG_NAME M_I_CPU1_SB_DQ<2>
J 0
(-6015 2260);
DISPLAY 0.659574 (-6015 2260);
PAINT MONO (-6015 2260);
DISPLAY INVISIBLE (-6015 2260);
FORCEPROP 1 LASTPIN (-6025 2250) BN 2
J 0
(-6037 2258);
DISPLAY 0.489362 (-6037 2258);
PAINT GREEN (-6037 2258);
FORCEPROP 2 LAST CDS_LIB mstr_standard
J 0
(-5975 2250);
DISPLAY 0.723404 (-5975 2250);
PAINT MONO (-5975 2250);
DISPLAY INVISIBLE (-5975 2250);
FORCEPROP 1 LAST BODY_TYPE PLUMBING
J 0
(-5975 2300);
DISPLAY 0.872340 (-5975 2300);
PAINT GREEN (-5975 2300);
DISPLAY INVISIBLE (-5975 2300);
FORCEPROP 1 LAST HDL_TAP TRUE
J 0
(-5650 2125);
DISPLAY 0.872340 (-5650 2125);
DISPLAY INVISIBLE (-5650 2125);
FORCEPROP 1 LAST PATH I36
J 0
(-5977 2250);
DISPLAY 0.872340 (-5977 2250);
PAINT GREEN (-5977 2250);
DISPLAY INVISIBLE (-5977 2250);
FORCEADD TAP..1
(-5975 2200);
FORCEPROP 3 LASTPIN (-6025 2200) SIG_NAME M_I_CPU1_SB_DQ<1>
J 0
(-6015 2210);
DISPLAY 0.659574 (-6015 2210);
PAINT MONO (-6015 2210);
DISPLAY INVISIBLE (-6015 2210);
FORCEPROP 1 LASTPIN (-6025 2200) BN 1
J 0
(-6037 2208);
DISPLAY 0.489362 (-6037 2208);
PAINT GREEN (-6037 2208);
FORCEPROP 2 LAST CDS_LIB mstr_standard
J 0
(-5975 2200);
DISPLAY 0.723404 (-5975 2200);
PAINT MONO (-5975 2200);
DISPLAY INVISIBLE (-5975 2200);
FORCEPROP 1 LAST BODY_TYPE PLUMBING
J 0
(-5975 2250);
DISPLAY 0.872340 (-5975 2250);
PAINT GREEN (-5975 2250);
DISPLAY INVISIBLE (-5975 2250);
FORCEPROP 1 LAST HDL_TAP TRUE
J 0
(-5650 2075);
DISPLAY 0.872340 (-5650 2075);
DISPLAY INVISIBLE (-5650 2075);
FORCEPROP 1 LAST PATH I37
J 0
(-5977 2200);
DISPLAY 0.872340 (-5977 2200);
PAINT GREEN (-5977 2200);
DISPLAY INVISIBLE (-5977 2200);
FORCEADD TAP..1
(-5975 2350);
FORCEPROP 3 LASTPIN (-6025 2350) SIG_NAME M_I_CPU1_SB_DQ<4>
J 0
(-6015 2360);
DISPLAY 0.659574 (-6015 2360);
PAINT MONO (-6015 2360);
DISPLAY INVISIBLE (-6015 2360);
FORCEPROP 1 LASTPIN (-6025 2350) BN 4
J 0
(-6037 2358);
DISPLAY 0.489362 (-6037 2358);
PAINT GREEN (-6037 2358);
FORCEPROP 2 LAST CDS_LIB mstr_standard
J 0
(-5975 2350);
DISPLAY 0.723404 (-5975 2350);
PAINT MONO (-5975 2350);
DISPLAY INVISIBLE (-5975 2350);
FORCEPROP 1 LAST BODY_TYPE PLUMBING
J 0
(-5975 2400);
DISPLAY 0.872340 (-5975 2400);
PAINT GREEN (-5975 2400);
DISPLAY INVISIBLE (-5975 2400);
FORCEPROP 1 LAST HDL_TAP TRUE
J 0
(-5650 2225);
DISPLAY 0.872340 (-5650 2225);
DISPLAY INVISIBLE (-5650 2225);
FORCEPROP 1 LAST PATH I38
J 0
(-5977 2350);
DISPLAY 0.872340 (-5977 2350);
PAINT GREEN (-5977 2350);
DISPLAY INVISIBLE (-5977 2350);
FORCEADD TAP..1
(-5975 2300);
FORCEPROP 3 LASTPIN (-6025 2300) SIG_NAME M_I_CPU1_SB_DQ<3>
J 0
(-6015 2310);
DISPLAY 0.659574 (-6015 2310);
PAINT MONO (-6015 2310);
DISPLAY INVISIBLE (-6015 2310);
FORCEPROP 1 LASTPIN (-6025 2300) BN 3
J 0
(-6037 2308);
DISPLAY 0.489362 (-6037 2308);
PAINT GREEN (-6037 2308);
FORCEPROP 2 LAST CDS_LIB mstr_standard
J 0
(-5975 2300);
DISPLAY 0.723404 (-5975 2300);
PAINT MONO (-5975 2300);
DISPLAY INVISIBLE (-5975 2300);
FORCEPROP 1 LAST BODY_TYPE PLUMBING
J 0
(-5975 2350);
DISPLAY 0.872340 (-5975 2350);
PAINT GREEN (-5975 2350);
DISPLAY INVISIBLE (-5975 2350);
FORCEPROP 1 LAST HDL_TAP TRUE
J 0
(-5650 2175);
DISPLAY 0.872340 (-5650 2175);
DISPLAY INVISIBLE (-5650 2175);
FORCEPROP 1 LAST PATH I39
J 0
(-5977 2300);
DISPLAY 0.872340 (-5977 2300);
PAINT GREEN (-5977 2300);
DISPLAY INVISIBLE (-5977 2300);
FORCEADD TAP..1
(-5975 2400);
FORCEPROP 3 LASTPIN (-6025 2400) SIG_NAME M_I_CPU1_SB_DQ<5>
J 0
(-6015 2410);
DISPLAY 0.659574 (-6015 2410);
PAINT MONO (-6015 2410);
DISPLAY INVISIBLE (-6015 2410);
FORCEPROP 1 LASTPIN (-6025 2400) BN 5
J 0
(-6037 2408);
DISPLAY 0.489362 (-6037 2408);
PAINT GREEN (-6037 2408);
FORCEPROP 2 LAST CDS_LIB mstr_standard
J 0
(-5975 2400);
DISPLAY 0.723404 (-5975 2400);
PAINT MONO (-5975 2400);
DISPLAY INVISIBLE (-5975 2400);
FORCEPROP 1 LAST BODY_TYPE PLUMBING
J 0
(-5975 2450);
DISPLAY 0.872340 (-5975 2450);
PAINT GREEN (-5975 2450);
DISPLAY INVISIBLE (-5975 2450);
FORCEPROP 1 LAST HDL_TAP TRUE
J 0
(-5650 2275);
DISPLAY 0.872340 (-5650 2275);
DISPLAY INVISIBLE (-5650 2275);
FORCEPROP 1 LAST PATH I40
J 0
(-5977 2400);
DISPLAY 0.872340 (-5977 2400);
PAINT GREEN (-5977 2400);
DISPLAY INVISIBLE (-5977 2400);
FORCEADD TAP..1
(-5975 2450);
FORCEPROP 3 LASTPIN (-6025 2450) SIG_NAME M_I_CPU1_SB_DQ<6>
J 0
(-6015 2460);
DISPLAY 0.659574 (-6015 2460);
PAINT MONO (-6015 2460);
DISPLAY INVISIBLE (-6015 2460);
FORCEPROP 1 LASTPIN (-6025 2450) BN 6
J 0
(-6037 2458);
DISPLAY 0.489362 (-6037 2458);
PAINT GREEN (-6037 2458);
FORCEPROP 2 LAST CDS_LIB mstr_standard
J 0
(-5975 2450);
DISPLAY 0.723404 (-5975 2450);
PAINT MONO (-5975 2450);
DISPLAY INVISIBLE (-5975 2450);
FORCEPROP 1 LAST BODY_TYPE PLUMBING
J 0
(-5975 2500);
DISPLAY 0.872340 (-5975 2500);
PAINT GREEN (-5975 2500);
DISPLAY INVISIBLE (-5975 2500);
FORCEPROP 1 LAST HDL_TAP TRUE
J 0
(-5650 2325);
DISPLAY 0.872340 (-5650 2325);
DISPLAY INVISIBLE (-5650 2325);
FORCEPROP 1 LAST PATH I41
J 0
(-5977 2450);
DISPLAY 0.872340 (-5977 2450);
PAINT GREEN (-5977 2450);
DISPLAY INVISIBLE (-5977 2450);
FORCEADD TAP..1
(-5975 2500);
FORCEPROP 3 LASTPIN (-6025 2500) SIG_NAME M_I_CPU1_SB_DQ<7>
J 0
(-6015 2510);
DISPLAY 0.659574 (-6015 2510);
PAINT MONO (-6015 2510);
DISPLAY INVISIBLE (-6015 2510);
FORCEPROP 1 LASTPIN (-6025 2500) BN 7
J 0
(-6037 2508);
DISPLAY 0.489362 (-6037 2508);
PAINT GREEN (-6037 2508);
FORCEPROP 2 LAST CDS_LIB mstr_standard
J 0
(-5975 2500);
DISPLAY 0.723404 (-5975 2500);
PAINT MONO (-5975 2500);
DISPLAY INVISIBLE (-5975 2500);
FORCEPROP 1 LAST BODY_TYPE PLUMBING
J 0
(-5975 2550);
DISPLAY 0.872340 (-5975 2550);
PAINT GREEN (-5975 2550);
DISPLAY INVISIBLE (-5975 2550);
FORCEPROP 1 LAST HDL_TAP TRUE
J 0
(-5650 2375);
DISPLAY 0.872340 (-5650 2375);
DISPLAY INVISIBLE (-5650 2375);
FORCEPROP 1 LAST PATH I42
J 0
(-5977 2500);
DISPLAY 0.872340 (-5977 2500);
PAINT GREEN (-5977 2500);
DISPLAY INVISIBLE (-5977 2500);
FORCEADD TAP..1
(-5975 2600);
FORCEPROP 3 LASTPIN (-6025 2600) SIG_NAME M_I_CPU1_SB_DQ<9>
J 0
(-6015 2610);
DISPLAY 0.659574 (-6015 2610);
PAINT MONO (-6015 2610);
DISPLAY INVISIBLE (-6015 2610);
FORCEPROP 1 LASTPIN (-6025 2600) BN 9
J 0
(-6037 2608);
DISPLAY 0.489362 (-6037 2608);
PAINT GREEN (-6037 2608);
FORCEPROP 2 LAST CDS_LIB mstr_standard
J 0
(-5975 2600);
DISPLAY 0.723404 (-5975 2600);
PAINT MONO (-5975 2600);
DISPLAY INVISIBLE (-5975 2600);
FORCEPROP 1 LAST BODY_TYPE PLUMBING
J 0
(-5975 2650);
DISPLAY 0.872340 (-5975 2650);
PAINT GREEN (-5975 2650);
DISPLAY INVISIBLE (-5975 2650);
FORCEPROP 1 LAST HDL_TAP TRUE
J 0
(-5650 2475);
DISPLAY 0.872340 (-5650 2475);
DISPLAY INVISIBLE (-5650 2475);
FORCEPROP 1 LAST PATH I43
J 0
(-5977 2600);
DISPLAY 0.872340 (-5977 2600);
PAINT GREEN (-5977 2600);
DISPLAY INVISIBLE (-5977 2600);
FORCEADD TAP..1
(-5975 2550);
FORCEPROP 3 LASTPIN (-6025 2550) SIG_NAME M_I_CPU1_SB_DQ<8>
J 0
(-6015 2560);
DISPLAY 0.659574 (-6015 2560);
PAINT MONO (-6015 2560);
DISPLAY INVISIBLE (-6015 2560);
FORCEPROP 1 LASTPIN (-6025 2550) BN 8
J 0
(-6037 2558);
DISPLAY 0.489362 (-6037 2558);
PAINT GREEN (-6037 2558);
FORCEPROP 2 LAST CDS_LIB mstr_standard
J 0
(-5975 2550);
DISPLAY 0.723404 (-5975 2550);
PAINT MONO (-5975 2550);
DISPLAY INVISIBLE (-5975 2550);
FORCEPROP 1 LAST BODY_TYPE PLUMBING
J 0
(-5975 2600);
DISPLAY 0.872340 (-5975 2600);
PAINT GREEN (-5975 2600);
DISPLAY INVISIBLE (-5975 2600);
FORCEPROP 1 LAST HDL_TAP TRUE
J 0
(-5650 2425);
DISPLAY 0.872340 (-5650 2425);
DISPLAY INVISIBLE (-5650 2425);
FORCEPROP 1 LAST PATH I44
J 0
(-5977 2550);
DISPLAY 0.872340 (-5977 2550);
PAINT GREEN (-5977 2550);
DISPLAY INVISIBLE (-5977 2550);
FORCEADD TAP..1
(-5975 2650);
FORCEPROP 3 LASTPIN (-6025 2650) SIG_NAME M_I_CPU1_SB_DQ<10>
J 0
(-6015 2660);
DISPLAY 0.659574 (-6015 2660);
PAINT MONO (-6015 2660);
DISPLAY INVISIBLE (-6015 2660);
FORCEPROP 1 LASTPIN (-6025 2650) BN 10
J 0
(-6037 2658);
DISPLAY 0.489362 (-6037 2658);
PAINT GREEN (-6037 2658);
FORCEPROP 2 LAST CDS_LIB mstr_standard
J 0
(-5975 2650);
DISPLAY 0.723404 (-5975 2650);
PAINT MONO (-5975 2650);
DISPLAY INVISIBLE (-5975 2650);
FORCEPROP 1 LAST BODY_TYPE PLUMBING
J 0
(-5975 2700);
DISPLAY 0.872340 (-5975 2700);
PAINT GREEN (-5975 2700);
DISPLAY INVISIBLE (-5975 2700);
FORCEPROP 1 LAST HDL_TAP TRUE
J 0
(-5650 2525);
DISPLAY 0.872340 (-5650 2525);
DISPLAY INVISIBLE (-5650 2525);
FORCEPROP 1 LAST PATH I45
J 0
(-5977 2650);
DISPLAY 0.872340 (-5977 2650);
PAINT GREEN (-5977 2650);
DISPLAY INVISIBLE (-5977 2650);
FORCEADD TAP..1
(-5975 2750);
FORCEPROP 3 LASTPIN (-6025 2750) SIG_NAME M_I_CPU1_SB_DQ<12>
J 0
(-6015 2760);
DISPLAY 0.659574 (-6015 2760);
PAINT MONO (-6015 2760);
DISPLAY INVISIBLE (-6015 2760);
FORCEPROP 1 LASTPIN (-6025 2750) BN 12
J 0
(-6037 2758);
DISPLAY 0.489362 (-6037 2758);
PAINT GREEN (-6037 2758);
FORCEPROP 2 LAST CDS_LIB mstr_standard
J 0
(-5975 2750);
DISPLAY 0.723404 (-5975 2750);
PAINT MONO (-5975 2750);
DISPLAY INVISIBLE (-5975 2750);
FORCEPROP 1 LAST BODY_TYPE PLUMBING
J 0
(-5975 2800);
DISPLAY 0.872340 (-5975 2800);
PAINT GREEN (-5975 2800);
DISPLAY INVISIBLE (-5975 2800);
FORCEPROP 1 LAST HDL_TAP TRUE
J 0
(-5650 2625);
DISPLAY 0.872340 (-5650 2625);
DISPLAY INVISIBLE (-5650 2625);
FORCEPROP 1 LAST PATH I46
J 0
(-5977 2750);
DISPLAY 0.872340 (-5977 2750);
PAINT GREEN (-5977 2750);
DISPLAY INVISIBLE (-5977 2750);
FORCEADD TAP..1
(-5975 2700);
FORCEPROP 3 LASTPIN (-6025 2700) SIG_NAME M_I_CPU1_SB_DQ<11>
J 0
(-6015 2710);
DISPLAY 0.659574 (-6015 2710);
PAINT MONO (-6015 2710);
DISPLAY INVISIBLE (-6015 2710);
FORCEPROP 1 LASTPIN (-6025 2700) BN 11
J 0
(-6037 2708);
DISPLAY 0.489362 (-6037 2708);
PAINT GREEN (-6037 2708);
FORCEPROP 2 LAST CDS_LIB mstr_standard
J 0
(-5975 2700);
DISPLAY 0.723404 (-5975 2700);
PAINT MONO (-5975 2700);
DISPLAY INVISIBLE (-5975 2700);
FORCEPROP 1 LAST BODY_TYPE PLUMBING
J 0
(-5975 2750);
DISPLAY 0.872340 (-5975 2750);
PAINT GREEN (-5975 2750);
DISPLAY INVISIBLE (-5975 2750);
FORCEPROP 1 LAST HDL_TAP TRUE
J 0
(-5650 2575);
DISPLAY 0.872340 (-5650 2575);
DISPLAY INVISIBLE (-5650 2575);
FORCEPROP 1 LAST PATH I47
J 0
(-5977 2700);
DISPLAY 0.872340 (-5977 2700);
PAINT GREEN (-5977 2700);
DISPLAY INVISIBLE (-5977 2700);
FORCEADD TAP..1
(-5975 2850);
FORCEPROP 3 LASTPIN (-6025 2850) SIG_NAME M_I_CPU1_SB_DQ<14>
J 0
(-6015 2860);
DISPLAY 0.659574 (-6015 2860);
PAINT MONO (-6015 2860);
DISPLAY INVISIBLE (-6015 2860);
FORCEPROP 1 LASTPIN (-6025 2850) BN 14
J 0
(-6037 2858);
DISPLAY 0.489362 (-6037 2858);
PAINT GREEN (-6037 2858);
FORCEPROP 2 LAST CDS_LIB mstr_standard
J 0
(-5975 2850);
DISPLAY 0.723404 (-5975 2850);
PAINT MONO (-5975 2850);
DISPLAY INVISIBLE (-5975 2850);
FORCEPROP 1 LAST BODY_TYPE PLUMBING
J 0
(-5975 2900);
DISPLAY 0.872340 (-5975 2900);
PAINT GREEN (-5975 2900);
DISPLAY INVISIBLE (-5975 2900);
FORCEPROP 1 LAST HDL_TAP TRUE
J 0
(-5650 2725);
DISPLAY 0.872340 (-5650 2725);
DISPLAY INVISIBLE (-5650 2725);
FORCEPROP 1 LAST PATH I48
J 0
(-5977 2850);
DISPLAY 0.872340 (-5977 2850);
PAINT GREEN (-5977 2850);
DISPLAY INVISIBLE (-5977 2850);
FORCEADD TAP..1
(-5975 2800);
FORCEPROP 3 LASTPIN (-6025 2800) SIG_NAME M_I_CPU1_SB_DQ<13>
J 0
(-6015 2810);
DISPLAY 0.659574 (-6015 2810);
PAINT MONO (-6015 2810);
DISPLAY INVISIBLE (-6015 2810);
FORCEPROP 1 LASTPIN (-6025 2800) BN 13
J 0
(-6037 2808);
DISPLAY 0.489362 (-6037 2808);
PAINT GREEN (-6037 2808);
FORCEPROP 2 LAST CDS_LIB mstr_standard
J 0
(-5975 2800);
DISPLAY 0.723404 (-5975 2800);
PAINT MONO (-5975 2800);
DISPLAY INVISIBLE (-5975 2800);
FORCEPROP 1 LAST BODY_TYPE PLUMBING
J 0
(-5975 2850);
DISPLAY 0.872340 (-5975 2850);
PAINT GREEN (-5975 2850);
DISPLAY INVISIBLE (-5975 2850);
FORCEPROP 1 LAST HDL_TAP TRUE
J 0
(-5650 2675);
DISPLAY 0.872340 (-5650 2675);
DISPLAY INVISIBLE (-5650 2675);
FORCEPROP 1 LAST PATH I49
J 0
(-5977 2800);
DISPLAY 0.872340 (-5977 2800);
PAINT GREEN (-5977 2800);
DISPLAY INVISIBLE (-5977 2800);
FORCEADD TAP..1
(-5975 2900);
FORCEPROP 3 LASTPIN (-6025 2900) SIG_NAME M_I_CPU1_SB_DQ<15>
J 0
(-6015 2910);
DISPLAY 0.659574 (-6015 2910);
PAINT MONO (-6015 2910);
DISPLAY INVISIBLE (-6015 2910);
FORCEPROP 1 LASTPIN (-6025 2900) BN 15
J 0
(-6037 2908);
DISPLAY 0.489362 (-6037 2908);
PAINT GREEN (-6037 2908);
FORCEPROP 2 LAST CDS_LIB mstr_standard
J 0
(-5975 2900);
DISPLAY 0.723404 (-5975 2900);
PAINT MONO (-5975 2900);
DISPLAY INVISIBLE (-5975 2900);
FORCEPROP 1 LAST BODY_TYPE PLUMBING
J 0
(-5975 2950);
DISPLAY 0.872340 (-5975 2950);
PAINT GREEN (-5975 2950);
DISPLAY INVISIBLE (-5975 2950);
FORCEPROP 1 LAST HDL_TAP TRUE
J 0
(-5650 2775);
DISPLAY 0.872340 (-5650 2775);
DISPLAY INVISIBLE (-5650 2775);
FORCEPROP 1 LAST PATH I50
J 0
(-5977 2900);
DISPLAY 0.872340 (-5977 2900);
PAINT GREEN (-5977 2900);
DISPLAY INVISIBLE (-5977 2900);
FORCEADD TAP..1
(-5975 3000);
FORCEPROP 3 LASTPIN (-6025 3000) SIG_NAME M_I_CPU1_SB_DQ<17>
J 0
(-6015 3010);
DISPLAY 0.659574 (-6015 3010);
PAINT MONO (-6015 3010);
DISPLAY INVISIBLE (-6015 3010);
FORCEPROP 1 LASTPIN (-6025 3000) BN 17
J 0
(-6037 3008);
DISPLAY 0.489362 (-6037 3008);
PAINT GREEN (-6037 3008);
FORCEPROP 2 LAST CDS_LIB mstr_standard
J 0
(-5975 3000);
DISPLAY 0.723404 (-5975 3000);
PAINT MONO (-5975 3000);
DISPLAY INVISIBLE (-5975 3000);
FORCEPROP 1 LAST BODY_TYPE PLUMBING
J 0
(-5975 3050);
DISPLAY 0.872340 (-5975 3050);
PAINT GREEN (-5975 3050);
DISPLAY INVISIBLE (-5975 3050);
FORCEPROP 1 LAST HDL_TAP TRUE
J 0
(-5650 2875);
DISPLAY 0.872340 (-5650 2875);
DISPLAY INVISIBLE (-5650 2875);
FORCEPROP 1 LAST PATH I51
J 0
(-5977 3000);
DISPLAY 0.872340 (-5977 3000);
PAINT GREEN (-5977 3000);
DISPLAY INVISIBLE (-5977 3000);
FORCEADD TAP..1
(-5975 2950);
FORCEPROP 3 LASTPIN (-6025 2950) SIG_NAME M_I_CPU1_SB_DQ<16>
J 0
(-6015 2960);
DISPLAY 0.659574 (-6015 2960);
PAINT MONO (-6015 2960);
DISPLAY INVISIBLE (-6015 2960);
FORCEPROP 1 LASTPIN (-6025 2950) BN 16
J 0
(-6037 2958);
DISPLAY 0.489362 (-6037 2958);
PAINT GREEN (-6037 2958);
FORCEPROP 2 LAST CDS_LIB mstr_standard
J 0
(-5975 2950);
DISPLAY 0.723404 (-5975 2950);
PAINT MONO (-5975 2950);
DISPLAY INVISIBLE (-5975 2950);
FORCEPROP 1 LAST BODY_TYPE PLUMBING
J 0
(-5975 3000);
DISPLAY 0.872340 (-5975 3000);
PAINT GREEN (-5975 3000);
DISPLAY INVISIBLE (-5975 3000);
FORCEPROP 1 LAST HDL_TAP TRUE
J 0
(-5650 2825);
DISPLAY 0.872340 (-5650 2825);
DISPLAY INVISIBLE (-5650 2825);
FORCEPROP 1 LAST PATH I52
J 0
(-5977 2950);
DISPLAY 0.872340 (-5977 2950);
PAINT GREEN (-5977 2950);
DISPLAY INVISIBLE (-5977 2950);
FORCEADD TAP..1
(-5975 3150);
FORCEPROP 3 LASTPIN (-6025 3150) SIG_NAME M_I_CPU1_SB_DQ<20>
J 0
(-6015 3160);
DISPLAY 0.659574 (-6015 3160);
PAINT MONO (-6015 3160);
DISPLAY INVISIBLE (-6015 3160);
FORCEPROP 1 LASTPIN (-6025 3150) BN 20
J 0
(-6037 3158);
DISPLAY 0.489362 (-6037 3158);
PAINT GREEN (-6037 3158);
FORCEPROP 2 LAST CDS_LIB mstr_standard
J 0
(-5975 3150);
DISPLAY 0.723404 (-5975 3150);
PAINT MONO (-5975 3150);
DISPLAY INVISIBLE (-5975 3150);
FORCEPROP 1 LAST BODY_TYPE PLUMBING
J 0
(-5975 3200);
DISPLAY 0.872340 (-5975 3200);
PAINT GREEN (-5975 3200);
DISPLAY INVISIBLE (-5975 3200);
FORCEPROP 1 LAST HDL_TAP TRUE
J 0
(-5650 3025);
DISPLAY 0.872340 (-5650 3025);
DISPLAY INVISIBLE (-5650 3025);
FORCEPROP 1 LAST PATH I53
J 0
(-5977 3150);
DISPLAY 0.872340 (-5977 3150);
PAINT GREEN (-5977 3150);
DISPLAY INVISIBLE (-5977 3150);
FORCEADD TAP..1
(-5975 3100);
FORCEPROP 3 LASTPIN (-6025 3100) SIG_NAME M_I_CPU1_SB_DQ<19>
J 0
(-6015 3110);
DISPLAY 0.659574 (-6015 3110);
PAINT MONO (-6015 3110);
DISPLAY INVISIBLE (-6015 3110);
FORCEPROP 1 LASTPIN (-6025 3100) BN 19
J 0
(-6037 3108);
DISPLAY 0.489362 (-6037 3108);
PAINT GREEN (-6037 3108);
FORCEPROP 2 LAST CDS_LIB mstr_standard
J 0
(-5975 3100);
DISPLAY 0.723404 (-5975 3100);
PAINT MONO (-5975 3100);
DISPLAY INVISIBLE (-5975 3100);
FORCEPROP 1 LAST BODY_TYPE PLUMBING
J 0
(-5975 3150);
DISPLAY 0.872340 (-5975 3150);
PAINT GREEN (-5975 3150);
DISPLAY INVISIBLE (-5975 3150);
FORCEPROP 1 LAST HDL_TAP TRUE
J 0
(-5650 2975);
DISPLAY 0.872340 (-5650 2975);
DISPLAY INVISIBLE (-5650 2975);
FORCEPROP 1 LAST PATH I54
J 0
(-5977 3100);
DISPLAY 0.872340 (-5977 3100);
PAINT GREEN (-5977 3100);
DISPLAY INVISIBLE (-5977 3100);
FORCEADD TAP..1
(-5975 3050);
FORCEPROP 3 LASTPIN (-6025 3050) SIG_NAME M_I_CPU1_SB_DQ<18>
J 0
(-6015 3060);
DISPLAY 0.659574 (-6015 3060);
PAINT MONO (-6015 3060);
DISPLAY INVISIBLE (-6015 3060);
FORCEPROP 1 LASTPIN (-6025 3050) BN 18
J 0
(-6037 3058);
DISPLAY 0.489362 (-6037 3058);
PAINT GREEN (-6037 3058);
FORCEPROP 2 LAST CDS_LIB mstr_standard
J 0
(-5975 3050);
DISPLAY 0.723404 (-5975 3050);
PAINT MONO (-5975 3050);
DISPLAY INVISIBLE (-5975 3050);
FORCEPROP 1 LAST BODY_TYPE PLUMBING
J 0
(-5975 3100);
DISPLAY 0.872340 (-5975 3100);
PAINT GREEN (-5975 3100);
DISPLAY INVISIBLE (-5975 3100);
FORCEPROP 1 LAST HDL_TAP TRUE
J 0
(-5650 2925);
DISPLAY 0.872340 (-5650 2925);
DISPLAY INVISIBLE (-5650 2925);
FORCEPROP 1 LAST PATH I55
J 0
(-5977 3050);
DISPLAY 0.872340 (-5977 3050);
PAINT GREEN (-5977 3050);
DISPLAY INVISIBLE (-5977 3050);
FORCEADD TAP..1
(-5975 3200);
FORCEPROP 3 LASTPIN (-6025 3200) SIG_NAME M_I_CPU1_SB_DQ<21>
J 0
(-6015 3210);
DISPLAY 0.659574 (-6015 3210);
PAINT MONO (-6015 3210);
DISPLAY INVISIBLE (-6015 3210);
FORCEPROP 1 LASTPIN (-6025 3200) BN 21
J 0
(-6037 3208);
DISPLAY 0.489362 (-6037 3208);
PAINT GREEN (-6037 3208);
FORCEPROP 2 LAST CDS_LIB mstr_standard
J 0
(-5975 3200);
DISPLAY 0.723404 (-5975 3200);
PAINT MONO (-5975 3200);
DISPLAY INVISIBLE (-5975 3200);
FORCEPROP 1 LAST BODY_TYPE PLUMBING
J 0
(-5975 3250);
DISPLAY 0.872340 (-5975 3250);
PAINT GREEN (-5975 3250);
DISPLAY INVISIBLE (-5975 3250);
FORCEPROP 1 LAST HDL_TAP TRUE
J 0
(-5650 3075);
DISPLAY 0.872340 (-5650 3075);
DISPLAY INVISIBLE (-5650 3075);
FORCEPROP 1 LAST PATH I56
J 0
(-5977 3200);
DISPLAY 0.872340 (-5977 3200);
PAINT GREEN (-5977 3200);
DISPLAY INVISIBLE (-5977 3200);
FORCEADD TAP..1
(-5975 3250);
FORCEPROP 3 LASTPIN (-6025 3250) SIG_NAME M_I_CPU1_SB_DQ<22>
J 0
(-6015 3260);
DISPLAY 0.659574 (-6015 3260);
PAINT MONO (-6015 3260);
DISPLAY INVISIBLE (-6015 3260);
FORCEPROP 1 LASTPIN (-6025 3250) BN 22
J 0
(-6037 3258);
DISPLAY 0.489362 (-6037 3258);
PAINT GREEN (-6037 3258);
FORCEPROP 2 LAST CDS_LIB mstr_standard
J 0
(-5975 3250);
DISPLAY 0.723404 (-5975 3250);
PAINT MONO (-5975 3250);
DISPLAY INVISIBLE (-5975 3250);
FORCEPROP 1 LAST BODY_TYPE PLUMBING
J 0
(-5975 3300);
DISPLAY 0.872340 (-5975 3300);
PAINT GREEN (-5975 3300);
DISPLAY INVISIBLE (-5975 3300);
FORCEPROP 1 LAST HDL_TAP TRUE
J 0
(-5650 3125);
DISPLAY 0.872340 (-5650 3125);
DISPLAY INVISIBLE (-5650 3125);
FORCEPROP 1 LAST PATH I57
J 0
(-5977 3250);
DISPLAY 0.872340 (-5977 3250);
PAINT GREEN (-5977 3250);
DISPLAY INVISIBLE (-5977 3250);
FORCEADD TAP..1
(-5975 3400);
FORCEPROP 3 LASTPIN (-6025 3400) SIG_NAME M_I_CPU1_SB_DQ<25>
J 0
(-6015 3410);
DISPLAY 0.659574 (-6015 3410);
PAINT MONO (-6015 3410);
DISPLAY INVISIBLE (-6015 3410);
FORCEPROP 1 LASTPIN (-6025 3400) BN 25
J 0
(-6037 3408);
DISPLAY 0.489362 (-6037 3408);
PAINT GREEN (-6037 3408);
FORCEPROP 2 LAST CDS_LIB mstr_standard
J 0
(-5975 3400);
DISPLAY 0.723404 (-5975 3400);
PAINT MONO (-5975 3400);
DISPLAY INVISIBLE (-5975 3400);
FORCEPROP 1 LAST BODY_TYPE PLUMBING
J 0
(-5975 3450);
DISPLAY 0.872340 (-5975 3450);
PAINT GREEN (-5975 3450);
DISPLAY INVISIBLE (-5975 3450);
FORCEPROP 1 LAST HDL_TAP TRUE
J 0
(-5650 3275);
DISPLAY 0.872340 (-5650 3275);
DISPLAY INVISIBLE (-5650 3275);
FORCEPROP 1 LAST PATH I58
J 0
(-5977 3400);
DISPLAY 0.872340 (-5977 3400);
PAINT GREEN (-5977 3400);
DISPLAY INVISIBLE (-5977 3400);
FORCEADD TAP..1
(-5975 3350);
FORCEPROP 3 LASTPIN (-6025 3350) SIG_NAME M_I_CPU1_SB_DQ<24>
J 0
(-6015 3360);
DISPLAY 0.659574 (-6015 3360);
PAINT MONO (-6015 3360);
DISPLAY INVISIBLE (-6015 3360);
FORCEPROP 1 LASTPIN (-6025 3350) BN 24
J 0
(-6037 3358);
DISPLAY 0.489362 (-6037 3358);
PAINT GREEN (-6037 3358);
FORCEPROP 2 LAST CDS_LIB mstr_standard
J 0
(-5975 3350);
DISPLAY 0.723404 (-5975 3350);
PAINT MONO (-5975 3350);
DISPLAY INVISIBLE (-5975 3350);
FORCEPROP 1 LAST BODY_TYPE PLUMBING
J 0
(-5975 3400);
DISPLAY 0.872340 (-5975 3400);
PAINT GREEN (-5975 3400);
DISPLAY INVISIBLE (-5975 3400);
FORCEPROP 1 LAST HDL_TAP TRUE
J 0
(-5650 3225);
DISPLAY 0.872340 (-5650 3225);
DISPLAY INVISIBLE (-5650 3225);
FORCEPROP 1 LAST PATH I59
J 0
(-5977 3350);
DISPLAY 0.872340 (-5977 3350);
PAINT GREEN (-5977 3350);
DISPLAY INVISIBLE (-5977 3350);
FORCEADD OFFPAGE..1
(-8275 2850);
FORCEPROP 2 LAST $XR0 105 
J 0
(-8557 2850);
DISPLAY 0.638298 (-8557 2850);
PAINT MONO (-8557 2850);
FORCEPROP 2 LAST PATH I6
J 0
(-8550 2900);
DISPLAY 1.021277 (-8550 2900);
DISPLAY INVISIBLE (-8550 2900);
FORCEPROP 1 LAST COMMENT_BODY TRUE
J 0
(-8150 2750);
DISPLAY 0.872340 (-8150 2750);
PAINT GREEN (-8150 2750);
DISPLAY INVISIBLE (-8150 2750);
FORCEPROP 1 LAST OFFPAGE TRUE
J 0
(-7950 2725);
DISPLAY 0.872340 (-7950 2725);
PAINT GREEN (-7950 2725);
DISPLAY INVISIBLE (-7950 2725);
FORCEPROP 2 LAST CDS_LIB mstr_standard
J 0
(-8275 2850);
DISPLAY 0.808511 (-8275 2850);
DISPLAY INVISIBLE (-8275 2850);
FORCEADD TAP..1
(-5975 3300);
FORCEPROP 3 LASTPIN (-6025 3300) SIG_NAME M_I_CPU1_SB_DQ<23>
J 0
(-6015 3310);
DISPLAY 0.659574 (-6015 3310);
PAINT MONO (-6015 3310);
DISPLAY INVISIBLE (-6015 3310);
FORCEPROP 1 LASTPIN (-6025 3300) BN 23
J 0
(-6037 3308);
DISPLAY 0.489362 (-6037 3308);
PAINT GREEN (-6037 3308);
FORCEPROP 2 LAST CDS_LIB mstr_standard
J 0
(-5975 3300);
DISPLAY 0.723404 (-5975 3300);
PAINT MONO (-5975 3300);
DISPLAY INVISIBLE (-5975 3300);
FORCEPROP 1 LAST BODY_TYPE PLUMBING
J 0
(-5975 3350);
DISPLAY 0.872340 (-5975 3350);
PAINT GREEN (-5975 3350);
DISPLAY INVISIBLE (-5975 3350);
FORCEPROP 1 LAST HDL_TAP TRUE
J 0
(-5650 3175);
DISPLAY 0.872340 (-5650 3175);
DISPLAY INVISIBLE (-5650 3175);
FORCEPROP 1 LAST PATH I60
J 0
(-5977 3300);
DISPLAY 0.872340 (-5977 3300);
PAINT GREEN (-5977 3300);
DISPLAY INVISIBLE (-5977 3300);
FORCEADD TAP..1
(-5975 3450);
FORCEPROP 3 LASTPIN (-6025 3450) SIG_NAME M_I_CPU1_SB_DQ<26>
J 0
(-6015 3460);
DISPLAY 0.659574 (-6015 3460);
PAINT MONO (-6015 3460);
DISPLAY INVISIBLE (-6015 3460);
FORCEPROP 1 LASTPIN (-6025 3450) BN 26
J 0
(-6037 3458);
DISPLAY 0.489362 (-6037 3458);
PAINT GREEN (-6037 3458);
FORCEPROP 2 LAST CDS_LIB mstr_standard
J 0
(-5975 3450);
DISPLAY 0.723404 (-5975 3450);
PAINT MONO (-5975 3450);
DISPLAY INVISIBLE (-5975 3450);
FORCEPROP 1 LAST BODY_TYPE PLUMBING
J 0
(-5975 3500);
DISPLAY 0.872340 (-5975 3500);
PAINT GREEN (-5975 3500);
DISPLAY INVISIBLE (-5975 3500);
FORCEPROP 1 LAST HDL_TAP TRUE
J 0
(-5650 3325);
DISPLAY 0.872340 (-5650 3325);
DISPLAY INVISIBLE (-5650 3325);
FORCEPROP 1 LAST PATH I61
J 0
(-5977 3450);
DISPLAY 0.872340 (-5977 3450);
PAINT GREEN (-5977 3450);
DISPLAY INVISIBLE (-5977 3450);
FORCEADD TAP..1
(-5975 3500);
FORCEPROP 3 LASTPIN (-6025 3500) SIG_NAME M_I_CPU1_SB_DQ<27>
J 0
(-6015 3510);
DISPLAY 0.659574 (-6015 3510);
PAINT MONO (-6015 3510);
DISPLAY INVISIBLE (-6015 3510);
FORCEPROP 1 LASTPIN (-6025 3500) BN 27
J 0
(-6037 3508);
DISPLAY 0.489362 (-6037 3508);
PAINT GREEN (-6037 3508);
FORCEPROP 2 LAST CDS_LIB mstr_standard
J 0
(-5975 3500);
DISPLAY 0.723404 (-5975 3500);
PAINT MONO (-5975 3500);
DISPLAY INVISIBLE (-5975 3500);
FORCEPROP 1 LAST BODY_TYPE PLUMBING
J 0
(-5975 3550);
DISPLAY 0.872340 (-5975 3550);
PAINT GREEN (-5975 3550);
DISPLAY INVISIBLE (-5975 3550);
FORCEPROP 1 LAST HDL_TAP TRUE
J 0
(-5650 3375);
DISPLAY 0.872340 (-5650 3375);
DISPLAY INVISIBLE (-5650 3375);
FORCEPROP 1 LAST PATH I62
J 0
(-5977 3500);
DISPLAY 0.872340 (-5977 3500);
PAINT GREEN (-5977 3500);
DISPLAY INVISIBLE (-5977 3500);
FORCEADD TAP..1
(-5975 3650);
FORCEPROP 3 LASTPIN (-6025 3650) SIG_NAME M_I_CPU1_SB_DQ<30>
J 0
(-6015 3660);
DISPLAY 0.659574 (-6015 3660);
PAINT MONO (-6015 3660);
DISPLAY INVISIBLE (-6015 3660);
FORCEPROP 1 LASTPIN (-6025 3650) BN 30
J 0
(-6037 3658);
DISPLAY 0.489362 (-6037 3658);
PAINT GREEN (-6037 3658);
FORCEPROP 2 LAST CDS_LIB mstr_standard
J 0
(-5975 3650);
DISPLAY 0.723404 (-5975 3650);
PAINT MONO (-5975 3650);
DISPLAY INVISIBLE (-5975 3650);
FORCEPROP 1 LAST BODY_TYPE PLUMBING
J 0
(-5975 3700);
DISPLAY 0.872340 (-5975 3700);
PAINT GREEN (-5975 3700);
DISPLAY INVISIBLE (-5975 3700);
FORCEPROP 1 LAST HDL_TAP TRUE
J 0
(-5650 3525);
DISPLAY 0.872340 (-5650 3525);
DISPLAY INVISIBLE (-5650 3525);
FORCEPROP 1 LAST PATH I63
J 0
(-5977 3650);
DISPLAY 0.872340 (-5977 3650);
PAINT GREEN (-5977 3650);
DISPLAY INVISIBLE (-5977 3650);
FORCEADD TAP..1
(-5975 3600);
FORCEPROP 3 LASTPIN (-6025 3600) SIG_NAME M_I_CPU1_SB_DQ<29>
J 0
(-6015 3610);
DISPLAY 0.659574 (-6015 3610);
PAINT MONO (-6015 3610);
DISPLAY INVISIBLE (-6015 3610);
FORCEPROP 1 LASTPIN (-6025 3600) BN 29
J 0
(-6037 3608);
DISPLAY 0.489362 (-6037 3608);
PAINT GREEN (-6037 3608);
FORCEPROP 2 LAST CDS_LIB mstr_standard
J 0
(-5975 3600);
DISPLAY 0.723404 (-5975 3600);
PAINT MONO (-5975 3600);
DISPLAY INVISIBLE (-5975 3600);
FORCEPROP 1 LAST BODY_TYPE PLUMBING
J 0
(-5975 3650);
DISPLAY 0.872340 (-5975 3650);
PAINT GREEN (-5975 3650);
DISPLAY INVISIBLE (-5975 3650);
FORCEPROP 1 LAST HDL_TAP TRUE
J 0
(-5650 3475);
DISPLAY 0.872340 (-5650 3475);
DISPLAY INVISIBLE (-5650 3475);
FORCEPROP 1 LAST PATH I64
J 0
(-5977 3600);
DISPLAY 0.872340 (-5977 3600);
PAINT GREEN (-5977 3600);
DISPLAY INVISIBLE (-5977 3600);
FORCEADD TAP..1
(-5975 3550);
FORCEPROP 3 LASTPIN (-6025 3550) SIG_NAME M_I_CPU1_SB_DQ<28>
J 0
(-6015 3560);
DISPLAY 0.659574 (-6015 3560);
PAINT MONO (-6015 3560);
DISPLAY INVISIBLE (-6015 3560);
FORCEPROP 1 LASTPIN (-6025 3550) BN 28
J 0
(-6037 3558);
DISPLAY 0.489362 (-6037 3558);
PAINT GREEN (-6037 3558);
FORCEPROP 2 LAST CDS_LIB mstr_standard
J 0
(-5975 3550);
DISPLAY 0.723404 (-5975 3550);
PAINT MONO (-5975 3550);
DISPLAY INVISIBLE (-5975 3550);
FORCEPROP 1 LAST BODY_TYPE PLUMBING
J 0
(-5975 3600);
DISPLAY 0.872340 (-5975 3600);
PAINT GREEN (-5975 3600);
DISPLAY INVISIBLE (-5975 3600);
FORCEPROP 1 LAST HDL_TAP TRUE
J 0
(-5650 3425);
DISPLAY 0.872340 (-5650 3425);
DISPLAY INVISIBLE (-5650 3425);
FORCEPROP 1 LAST PATH I65
J 0
(-5977 3550);
DISPLAY 0.872340 (-5977 3550);
PAINT GREEN (-5977 3550);
DISPLAY INVISIBLE (-5977 3550);
FORCEADD TAP..1
(-5975 3700);
FORCEPROP 3 LASTPIN (-6025 3700) SIG_NAME M_I_CPU1_SB_DQ<31>
J 0
(-6015 3710);
DISPLAY 0.659574 (-6015 3710);
PAINT MONO (-6015 3710);
DISPLAY INVISIBLE (-6015 3710);
FORCEPROP 1 LASTPIN (-6025 3700) BN 31
J 0
(-6037 3708);
DISPLAY 0.489362 (-6037 3708);
PAINT GREEN (-6037 3708);
FORCEPROP 2 LAST CDS_LIB mstr_standard
J 0
(-5975 3700);
DISPLAY 0.723404 (-5975 3700);
PAINT MONO (-5975 3700);
DISPLAY INVISIBLE (-5975 3700);
FORCEPROP 1 LAST BODY_TYPE PLUMBING
J 0
(-5975 3750);
DISPLAY 0.872340 (-5975 3750);
PAINT GREEN (-5975 3750);
DISPLAY INVISIBLE (-5975 3750);
FORCEPROP 1 LAST HDL_TAP TRUE
J 0
(-5650 3575);
DISPLAY 0.872340 (-5650 3575);
DISPLAY INVISIBLE (-5650 3575);
FORCEPROP 1 LAST PATH I66
J 0
(-5977 3700);
DISPLAY 0.872340 (-5977 3700);
PAINT GREEN (-5977 3700);
DISPLAY INVISIBLE (-5977 3700);
FORCEADD OFFPAGE..5
(-8125 3000);
FORCEPROP 2 LAST $XR0 45 
J 0
(-8349 3000);
DISPLAY 0.638298 (-8349 3000);
PAINT MONO (-8349 3000);
FORCEPROP 2 LAST PATH I7
J 0
(-8450 3050);
DISPLAY 1.021277 (-8450 3050);
DISPLAY INVISIBLE (-8450 3050);
FORCEPROP 1 LAST COMMENT_BODY TRUE
J 0
(-8025 2925);
DISPLAY 0.872340 (-8025 2925);
PAINT GREEN (-8025 2925);
DISPLAY INVISIBLE (-8025 2925);
FORCEPROP 1 LAST OFFPAGE TRUE
J 0
(-7800 2875);
DISPLAY 0.872340 (-7800 2875);
PAINT GREEN (-7800 2875);
DISPLAY INVISIBLE (-7800 2875);
FORCEPROP 2 LAST CDS_LIB mstr_standard
J 0
(-8125 3000);
DISPLAY INVISIBLE (-8125 3000);
FORCEADD OFFPAGE..3
(-5275 3750);
FORCEPROP 2 LAST $XR0 45 
J 0
(-4971 3750);
DISPLAY 0.638298 (-4971 3750);
PAINT MONO (-4971 3750);
FORCEPROP 2 LAST PATH I74
J 0
(-5050 3800);
DISPLAY 1.021277 (-5050 3800);
DISPLAY INVISIBLE (-5050 3800);
FORCEPROP 1 LAST COMMENT_BODY TRUE
J 0
(-5325 3650);
DISPLAY 0.872340 (-5325 3650);
PAINT GREEN (-5325 3650);
DISPLAY INVISIBLE (-5325 3650);
FORCEPROP 1 LAST OFFPAGE TRUE
J 0
(-4950 3625);
DISPLAY 0.872340 (-4950 3625);
PAINT GREEN (-4950 3625);
DISPLAY INVISIBLE (-4950 3625);
FORCEPROP 2 LAST CDS_LIB mstr_standard
J 0
(-5275 3750);
DISPLAY 0.723404 (-5275 3750);
PAINT MONO (-5275 3750);
DISPLAY INVISIBLE (-5275 3750);
FORCEADD TAP..1
R 2
(-7675 3800);
FORCEPROP 3 LASTPIN (-7625 3800) SIG_NAME M_I_CPU1_SA_CB<4>
J 0
(-7615 3810);
DISPLAY 0.659574 (-7615 3810);
PAINT MONO (-7615 3810);
DISPLAY INVISIBLE (-7615 3810);
FORCEPROP 1 LASTPIN (-7625 3800) BN 4
J 2
(-7613 3808);
DISPLAY 0.489362 (-7613 3808);
PAINT GREEN (-7613 3808);
FORCEPROP 2 LAST CDS_LIB mstr_standard
J 0
(-7675 3800);
DISPLAY 0.723404 (-7675 3800);
PAINT MONO (-7675 3800);
DISPLAY INVISIBLE (-7675 3800);
FORCEPROP 1 LAST BODY_TYPE PLUMBING
J 2
(-7675 3850);
DISPLAY 0.872340 (-7675 3850);
PAINT GREEN (-7675 3850);
DISPLAY INVISIBLE (-7675 3850);
FORCEPROP 1 LAST HDL_TAP TRUE
J 2
(-8000 3675);
DISPLAY 0.872340 (-8000 3675);
DISPLAY INVISIBLE (-8000 3675);
FORCEPROP 1 LAST PATH I75
J 2
(-7673 3800);
DISPLAY 0.872340 (-7673 3800);
PAINT GREEN (-7673 3800);
DISPLAY INVISIBLE (-7673 3800);
FORCEADD TAP..1
R 2
(-7675 3850);
FORCEPROP 3 LASTPIN (-7625 3850) SIG_NAME M_I_CPU1_SA_CB<5>
J 0
(-7615 3860);
DISPLAY 0.659574 (-7615 3860);
PAINT MONO (-7615 3860);
DISPLAY INVISIBLE (-7615 3860);
FORCEPROP 1 LASTPIN (-7625 3850) BN 5
J 2
(-7613 3858);
DISPLAY 0.489362 (-7613 3858);
PAINT GREEN (-7613 3858);
FORCEPROP 2 LAST CDS_LIB mstr_standard
J 0
(-7675 3850);
DISPLAY 0.723404 (-7675 3850);
PAINT MONO (-7675 3850);
DISPLAY INVISIBLE (-7675 3850);
FORCEPROP 1 LAST BODY_TYPE PLUMBING
J 2
(-7675 3900);
DISPLAY 0.872340 (-7675 3900);
PAINT GREEN (-7675 3900);
DISPLAY INVISIBLE (-7675 3900);
FORCEPROP 1 LAST HDL_TAP TRUE
J 2
(-8000 3725);
DISPLAY 0.872340 (-8000 3725);
DISPLAY INVISIBLE (-8000 3725);
FORCEPROP 1 LAST PATH I76
J 2
(-7673 3850);
DISPLAY 0.872340 (-7673 3850);
PAINT GREEN (-7673 3850);
DISPLAY INVISIBLE (-7673 3850);
FORCEADD TAP..1
R 2
(-7675 3900);
FORCEPROP 3 LASTPIN (-7625 3900) SIG_NAME M_I_CPU1_SA_CB<6>
J 0
(-7615 3910);
DISPLAY 0.659574 (-7615 3910);
PAINT MONO (-7615 3910);
DISPLAY INVISIBLE (-7615 3910);
FORCEPROP 1 LASTPIN (-7625 3900) BN 6
J 2
(-7613 3908);
DISPLAY 0.489362 (-7613 3908);
PAINT GREEN (-7613 3908);
FORCEPROP 2 LAST CDS_LIB mstr_standard
J 0
(-7675 3900);
DISPLAY 0.723404 (-7675 3900);
PAINT MONO (-7675 3900);
DISPLAY INVISIBLE (-7675 3900);
FORCEPROP 1 LAST BODY_TYPE PLUMBING
J 2
(-7675 3950);
DISPLAY 0.872340 (-7675 3950);
PAINT GREEN (-7675 3950);
DISPLAY INVISIBLE (-7675 3950);
FORCEPROP 1 LAST HDL_TAP TRUE
J 2
(-8000 3775);
DISPLAY 0.872340 (-8000 3775);
DISPLAY INVISIBLE (-8000 3775);
FORCEPROP 1 LAST PATH I77
J 2
(-7673 3900);
DISPLAY 0.872340 (-7673 3900);
PAINT GREEN (-7673 3900);
DISPLAY INVISIBLE (-7673 3900);
FORCEADD TAP..1
R 2
(-7675 3950);
FORCEPROP 3 LASTPIN (-7625 3950) SIG_NAME M_I_CPU1_SA_CB<7>
J 0
(-7615 3960);
DISPLAY 0.659574 (-7615 3960);
PAINT MONO (-7615 3960);
DISPLAY INVISIBLE (-7615 3960);
FORCEPROP 1 LASTPIN (-7625 3950) BN 7
J 2
(-7613 3958);
DISPLAY 0.489362 (-7613 3958);
PAINT GREEN (-7613 3958);
FORCEPROP 2 LAST CDS_LIB mstr_standard
J 0
(-7675 3950);
DISPLAY 0.723404 (-7675 3950);
PAINT MONO (-7675 3950);
DISPLAY INVISIBLE (-7675 3950);
FORCEPROP 1 LAST BODY_TYPE PLUMBING
J 2
(-7675 4000);
DISPLAY 0.872340 (-7675 4000);
PAINT GREEN (-7675 4000);
DISPLAY INVISIBLE (-7675 4000);
FORCEPROP 1 LAST HDL_TAP TRUE
J 2
(-8000 3825);
DISPLAY 0.872340 (-8000 3825);
DISPLAY INVISIBLE (-8000 3825);
FORCEPROP 1 LAST PATH I78
J 2
(-7673 3950);
DISPLAY 0.872340 (-7673 3950);
PAINT GREEN (-7673 3950);
DISPLAY INVISIBLE (-7673 3950);
FORCEADD TAP..1
R 2
(-7675 4650);
FORCEPROP 3 LASTPIN (-7625 4650) SIG_NAME M_I_CPU1_SB_CA<0>
J 0
(-7615 4660);
DISPLAY 0.659574 (-7615 4660);
PAINT MONO (-7615 4660);
DISPLAY INVISIBLE (-7615 4660);
FORCEPROP 1 LASTPIN (-7625 4650) BN 0
J 2
(-7613 4658);
DISPLAY 0.489362 (-7613 4658);
PAINT GREEN (-7613 4658);
FORCEPROP 2 LAST CDS_LIB mstr_standard
J 0
(-7675 4650);
DISPLAY 0.723404 (-7675 4650);
PAINT MONO (-7675 4650);
DISPLAY INVISIBLE (-7675 4650);
FORCEPROP 1 LAST BODY_TYPE PLUMBING
J 2
(-7675 4700);
DISPLAY 0.872340 (-7675 4700);
PAINT GREEN (-7675 4700);
DISPLAY INVISIBLE (-7675 4700);
FORCEPROP 1 LAST HDL_TAP TRUE
J 2
(-8000 4525);
DISPLAY 0.872340 (-8000 4525);
DISPLAY INVISIBLE (-8000 4525);
FORCEPROP 1 LAST PATH I79
J 2
(-7673 4650);
DISPLAY 0.872340 (-7673 4650);
PAINT GREEN (-7673 4650);
DISPLAY INVISIBLE (-7673 4650);
FORCEADD OFFPAGE..1
(-8125 3050);
FORCEPROP 2 LAST $XR0 45 
J 0
(-8376 3050);
DISPLAY 0.638298 (-8376 3050);
PAINT MONO (-8376 3050);
FORCEPROP 2 LAST PATH I8
J 0
(-8325 3100);
DISPLAY 1.021277 (-8325 3100);
DISPLAY INVISIBLE (-8325 3100);
FORCEPROP 1 LAST COMMENT_BODY TRUE
J 0
(-8000 2950);
DISPLAY 0.872340 (-8000 2950);
PAINT GREEN (-8000 2950);
DISPLAY INVISIBLE (-8000 2950);
FORCEPROP 1 LAST OFFPAGE TRUE
J 0
(-7800 2925);
DISPLAY 0.872340 (-7800 2925);
PAINT GREEN (-7800 2925);
DISPLAY INVISIBLE (-7800 2925);
FORCEPROP 2 LAST CDS_LIB mstr_standard
J 0
(-8125 3050);
DISPLAY 0.808511 (-8125 3050);
DISPLAY INVISIBLE (-8125 3050);
FORCEADD TAP..1
R 2
(-7675 4700);
FORCEPROP 3 LASTPIN (-7625 4700) SIG_NAME M_I_CPU1_SB_CA<1>
J 0
(-7615 4710);
DISPLAY 0.659574 (-7615 4710);
PAINT MONO (-7615 4710);
DISPLAY INVISIBLE (-7615 4710);
FORCEPROP 1 LASTPIN (-7625 4700) BN 1
J 2
(-7613 4708);
DISPLAY 0.489362 (-7613 4708);
PAINT GREEN (-7613 4708);
FORCEPROP 2 LAST CDS_LIB mstr_standard
J 0
(-7675 4700);
DISPLAY 0.723404 (-7675 4700);
PAINT MONO (-7675 4700);
DISPLAY INVISIBLE (-7675 4700);
FORCEPROP 1 LAST BODY_TYPE PLUMBING
J 2
(-7675 4750);
DISPLAY 0.872340 (-7675 4750);
PAINT GREEN (-7675 4750);
DISPLAY INVISIBLE (-7675 4750);
FORCEPROP 1 LAST HDL_TAP TRUE
J 2
(-8000 4575);
DISPLAY 0.872340 (-8000 4575);
DISPLAY INVISIBLE (-8000 4575);
FORCEPROP 1 LAST PATH I80
J 2
(-7673 4700);
DISPLAY 0.872340 (-7673 4700);
PAINT GREEN (-7673 4700);
DISPLAY INVISIBLE (-7673 4700);
FORCEADD TAP..1
R 2
(-7675 4750);
FORCEPROP 3 LASTPIN (-7625 4750) SIG_NAME M_I_CPU1_SB_CA<2>
J 0
(-7615 4760);
DISPLAY 0.659574 (-7615 4760);
PAINT MONO (-7615 4760);
DISPLAY INVISIBLE (-7615 4760);
FORCEPROP 1 LASTPIN (-7625 4750) BN 2
J 2
(-7613 4758);
DISPLAY 0.489362 (-7613 4758);
PAINT GREEN (-7613 4758);
FORCEPROP 2 LAST CDS_LIB mstr_standard
J 0
(-7675 4750);
DISPLAY 0.723404 (-7675 4750);
PAINT MONO (-7675 4750);
DISPLAY INVISIBLE (-7675 4750);
FORCEPROP 1 LAST BODY_TYPE PLUMBING
J 2
(-7675 4800);
DISPLAY 0.872340 (-7675 4800);
PAINT GREEN (-7675 4800);
DISPLAY INVISIBLE (-7675 4800);
FORCEPROP 1 LAST HDL_TAP TRUE
J 2
(-8000 4625);
DISPLAY 0.872340 (-8000 4625);
DISPLAY INVISIBLE (-8000 4625);
FORCEPROP 1 LAST PATH I81
J 2
(-7673 4750);
DISPLAY 0.872340 (-7673 4750);
PAINT GREEN (-7673 4750);
DISPLAY INVISIBLE (-7673 4750);
FORCEADD TAP..1
R 2
(-7675 4800);
FORCEPROP 3 LASTPIN (-7625 4800) SIG_NAME M_I_CPU1_SB_CA<3>
J 0
(-7615 4810);
DISPLAY 0.659574 (-7615 4810);
PAINT MONO (-7615 4810);
DISPLAY INVISIBLE (-7615 4810);
FORCEPROP 1 LASTPIN (-7625 4800) BN 3
J 2
(-7613 4808);
DISPLAY 0.489362 (-7613 4808);
PAINT GREEN (-7613 4808);
FORCEPROP 2 LAST CDS_LIB mstr_standard
J 0
(-7675 4800);
DISPLAY 0.723404 (-7675 4800);
PAINT MONO (-7675 4800);
DISPLAY INVISIBLE (-7675 4800);
FORCEPROP 1 LAST BODY_TYPE PLUMBING
J 2
(-7675 4850);
DISPLAY 0.872340 (-7675 4850);
PAINT GREEN (-7675 4850);
DISPLAY INVISIBLE (-7675 4850);
FORCEPROP 1 LAST HDL_TAP TRUE
J 2
(-8000 4675);
DISPLAY 0.872340 (-8000 4675);
DISPLAY INVISIBLE (-8000 4675);
FORCEPROP 1 LAST PATH I82
J 2
(-7673 4800);
DISPLAY 0.872340 (-7673 4800);
PAINT GREEN (-7673 4800);
DISPLAY INVISIBLE (-7673 4800);
FORCEADD TAP..1
R 2
(-7675 4850);
FORCEPROP 3 LASTPIN (-7625 4850) SIG_NAME M_I_CPU1_SB_CA<4>
J 0
(-7615 4860);
DISPLAY 0.659574 (-7615 4860);
PAINT MONO (-7615 4860);
DISPLAY INVISIBLE (-7615 4860);
FORCEPROP 1 LASTPIN (-7625 4850) BN 4
J 2
(-7613 4858);
DISPLAY 0.489362 (-7613 4858);
PAINT GREEN (-7613 4858);
FORCEPROP 2 LAST CDS_LIB mstr_standard
J 0
(-7675 4850);
DISPLAY 0.723404 (-7675 4850);
PAINT MONO (-7675 4850);
DISPLAY INVISIBLE (-7675 4850);
FORCEPROP 1 LAST BODY_TYPE PLUMBING
J 2
(-7675 4900);
DISPLAY 0.872340 (-7675 4900);
PAINT GREEN (-7675 4900);
DISPLAY INVISIBLE (-7675 4900);
FORCEPROP 1 LAST HDL_TAP TRUE
J 2
(-8000 4725);
DISPLAY 0.872340 (-8000 4725);
DISPLAY INVISIBLE (-8000 4725);
FORCEPROP 1 LAST PATH I83
J 2
(-7673 4850);
DISPLAY 0.872340 (-7673 4850);
PAINT GREEN (-7673 4850);
DISPLAY INVISIBLE (-7673 4850);
FORCEADD TAP..1
R 2
(-7675 4900);
FORCEPROP 3 LASTPIN (-7625 4900) SIG_NAME M_I_CPU1_SB_CA<5>
J 0
(-7615 4910);
DISPLAY 0.659574 (-7615 4910);
PAINT MONO (-7615 4910);
DISPLAY INVISIBLE (-7615 4910);
FORCEPROP 1 LASTPIN (-7625 4900) BN 5
J 2
(-7613 4908);
DISPLAY 0.489362 (-7613 4908);
PAINT GREEN (-7613 4908);
FORCEPROP 2 LAST CDS_LIB mstr_standard
J 0
(-7675 4900);
DISPLAY 0.723404 (-7675 4900);
PAINT MONO (-7675 4900);
DISPLAY INVISIBLE (-7675 4900);
FORCEPROP 1 LAST BODY_TYPE PLUMBING
J 2
(-7675 4950);
DISPLAY 0.872340 (-7675 4950);
PAINT GREEN (-7675 4950);
DISPLAY INVISIBLE (-7675 4950);
FORCEPROP 1 LAST HDL_TAP TRUE
J 2
(-8000 4775);
DISPLAY 0.872340 (-8000 4775);
DISPLAY INVISIBLE (-8000 4775);
FORCEPROP 1 LAST PATH I84
J 2
(-7673 4900);
DISPLAY 0.872340 (-7673 4900);
PAINT GREEN (-7673 4900);
DISPLAY INVISIBLE (-7673 4900);
FORCEADD TAP..1
R 2
(-7675 4950);
FORCEPROP 3 LASTPIN (-7625 4950) SIG_NAME M_I_CPU1_SB_CA<6>
J 0
(-7615 4960);
DISPLAY 0.659574 (-7615 4960);
PAINT MONO (-7615 4960);
DISPLAY INVISIBLE (-7615 4960);
FORCEPROP 1 LASTPIN (-7625 4950) BN 6
J 2
(-7613 4958);
DISPLAY 0.489362 (-7613 4958);
PAINT GREEN (-7613 4958);
FORCEPROP 2 LAST CDS_LIB mstr_standard
J 0
(-7675 4950);
DISPLAY 0.723404 (-7675 4950);
PAINT MONO (-7675 4950);
DISPLAY INVISIBLE (-7675 4950);
FORCEPROP 1 LAST BODY_TYPE PLUMBING
J 2
(-7675 5000);
DISPLAY 0.872340 (-7675 5000);
PAINT GREEN (-7675 5000);
DISPLAY INVISIBLE (-7675 5000);
FORCEPROP 1 LAST HDL_TAP TRUE
J 2
(-8000 4825);
DISPLAY 0.872340 (-8000 4825);
DISPLAY INVISIBLE (-8000 4825);
FORCEPROP 1 LAST PATH I85
J 2
(-7673 4950);
DISPLAY 0.872340 (-7673 4950);
PAINT GREEN (-7673 4950);
DISPLAY INVISIBLE (-7673 4950);
FORCEADD TAP..1
R 2
(-7675 5050);
FORCEPROP 3 LASTPIN (-7625 5050) SIG_NAME M_I_CPU1_SA_CA<0>
J 0
(-7615 5060);
DISPLAY 0.659574 (-7615 5060);
PAINT MONO (-7615 5060);
DISPLAY INVISIBLE (-7615 5060);
FORCEPROP 1 LASTPIN (-7625 5050) BN 0
J 2
(-7613 5058);
DISPLAY 0.489362 (-7613 5058);
PAINT GREEN (-7613 5058);
FORCEPROP 2 LAST CDS_LIB mstr_standard
J 0
(-7675 5050);
DISPLAY 0.723404 (-7675 5050);
PAINT MONO (-7675 5050);
DISPLAY INVISIBLE (-7675 5050);
FORCEPROP 1 LAST BODY_TYPE PLUMBING
J 2
(-7675 5100);
DISPLAY 0.872340 (-7675 5100);
PAINT GREEN (-7675 5100);
DISPLAY INVISIBLE (-7675 5100);
FORCEPROP 1 LAST HDL_TAP TRUE
J 2
(-8000 4925);
DISPLAY 0.872340 (-8000 4925);
DISPLAY INVISIBLE (-8000 4925);
FORCEPROP 1 LAST PATH I86
J 2
(-7673 5050);
DISPLAY 0.872340 (-7673 5050);
PAINT GREEN (-7673 5050);
DISPLAY INVISIBLE (-7673 5050);
FORCEADD TAP..1
R 2
(-7675 5100);
FORCEPROP 3 LASTPIN (-7625 5100) SIG_NAME M_I_CPU1_SA_CA<1>
J 0
(-7615 5110);
DISPLAY 0.659574 (-7615 5110);
PAINT MONO (-7615 5110);
DISPLAY INVISIBLE (-7615 5110);
FORCEPROP 1 LASTPIN (-7625 5100) BN 1
J 2
(-7613 5108);
DISPLAY 0.489362 (-7613 5108);
PAINT GREEN (-7613 5108);
FORCEPROP 2 LAST CDS_LIB mstr_standard
J 0
(-7675 5100);
DISPLAY 0.723404 (-7675 5100);
PAINT MONO (-7675 5100);
DISPLAY INVISIBLE (-7675 5100);
FORCEPROP 1 LAST BODY_TYPE PLUMBING
J 2
(-7675 5150);
DISPLAY 0.872340 (-7675 5150);
PAINT GREEN (-7675 5150);
DISPLAY INVISIBLE (-7675 5150);
FORCEPROP 1 LAST HDL_TAP TRUE
J 2
(-8000 4975);
DISPLAY 0.872340 (-8000 4975);
DISPLAY INVISIBLE (-8000 4975);
FORCEPROP 1 LAST PATH I87
J 2
(-7673 5100);
DISPLAY 0.872340 (-7673 5100);
PAINT GREEN (-7673 5100);
DISPLAY INVISIBLE (-7673 5100);
FORCEADD TAP..1
R 2
(-7675 5150);
FORCEPROP 3 LASTPIN (-7625 5150) SIG_NAME M_I_CPU1_SA_CA<2>
J 0
(-7615 5160);
DISPLAY 0.659574 (-7615 5160);
PAINT MONO (-7615 5160);
DISPLAY INVISIBLE (-7615 5160);
FORCEPROP 1 LASTPIN (-7625 5150) BN 2
J 2
(-7613 5158);
DISPLAY 0.489362 (-7613 5158);
PAINT GREEN (-7613 5158);
FORCEPROP 2 LAST CDS_LIB mstr_standard
J 0
(-7675 5150);
DISPLAY 0.723404 (-7675 5150);
PAINT MONO (-7675 5150);
DISPLAY INVISIBLE (-7675 5150);
FORCEPROP 1 LAST BODY_TYPE PLUMBING
J 2
(-7675 5200);
DISPLAY 0.872340 (-7675 5200);
PAINT GREEN (-7675 5200);
DISPLAY INVISIBLE (-7675 5200);
FORCEPROP 1 LAST HDL_TAP TRUE
J 2
(-8000 5025);
DISPLAY 0.872340 (-8000 5025);
DISPLAY INVISIBLE (-8000 5025);
FORCEPROP 1 LAST PATH I88
J 2
(-7673 5150);
DISPLAY 0.872340 (-7673 5150);
PAINT GREEN (-7673 5150);
DISPLAY INVISIBLE (-7673 5150);
FORCEADD TAP..1
R 2
(-7675 5200);
FORCEPROP 3 LASTPIN (-7625 5200) SIG_NAME M_I_CPU1_SA_CA<3>
J 0
(-7615 5210);
DISPLAY 0.659574 (-7615 5210);
PAINT MONO (-7615 5210);
DISPLAY INVISIBLE (-7615 5210);
FORCEPROP 1 LASTPIN (-7625 5200) BN 3
J 2
(-7613 5208);
DISPLAY 0.489362 (-7613 5208);
PAINT GREEN (-7613 5208);
FORCEPROP 2 LAST CDS_LIB mstr_standard
J 0
(-7675 5200);
DISPLAY 0.723404 (-7675 5200);
PAINT MONO (-7675 5200);
DISPLAY INVISIBLE (-7675 5200);
FORCEPROP 1 LAST BODY_TYPE PLUMBING
J 2
(-7675 5250);
DISPLAY 0.872340 (-7675 5250);
PAINT GREEN (-7675 5250);
DISPLAY INVISIBLE (-7675 5250);
FORCEPROP 1 LAST HDL_TAP TRUE
J 2
(-8000 5075);
DISPLAY 0.872340 (-8000 5075);
DISPLAY INVISIBLE (-8000 5075);
FORCEPROP 1 LAST PATH I89
J 2
(-7673 5200);
DISPLAY 0.872340 (-7673 5200);
PAINT GREEN (-7673 5200);
DISPLAY INVISIBLE (-7673 5200);
FORCEADD VCC_CORE..1
(-8450 3375);
FORCEPROP 3 LASTPIN (-8450 3325) SIG_NAME P3V3_STBY\g
J 0
(-8440 3335);
DISPLAY 0.659574 (-8440 3335);
PAINT MONO (-8440 3335);
DISPLAY INVISIBLE (-8440 3335);
FORCEPROP 1 LAST HDL_POWER P3V3_STBY
J 1
(-8450 3425);
DISPLAY 0.489362 (-8450 3425);
PAINT GREEN (-8450 3425);
FORCEPROP 2 LAST CDS_LIB mstr_symbols
J 0
(-8450 3375);
PAINT MONO (-8450 3375);
DISPLAY INVISIBLE (-8450 3375);
FORCEPROP 1 LAST PATH I9
J 0
(-8400 3400);
DISPLAY 0.872340 (-8400 3400);
PAINT AQUA (-8400 3400);
DISPLAY INVISIBLE (-8400 3400);
FORCEPROP 0 LAST VOLTAGE 3.3
J 0
(-8725 3525);
DISPLAY 1.021277 (-8725 3525);
PAINT SKYBLUE (-8725 3525);
DISPLAY INVISIBLE (-8725 3525);
FORCEPROP 2 LAST ROOM PVCCINFAON_CPU1_CTRL
J 0
(-8450 3475);
DISPLAY 0.808511 (-8450 3475);
PAINT RED (-8450 3475);
DISPLAY INVISIBLE (-8450 3475);
FORCEADD TAP..1
R 2
(-7675 5250);
FORCEPROP 3 LASTPIN (-7625 5250) SIG_NAME M_I_CPU1_SA_CA<4>
J 0
(-7615 5260);
DISPLAY 0.659574 (-7615 5260);
PAINT MONO (-7615 5260);
DISPLAY INVISIBLE (-7615 5260);
FORCEPROP 1 LASTPIN (-7625 5250) BN 4
J 2
(-7613 5258);
DISPLAY 0.489362 (-7613 5258);
PAINT GREEN (-7613 5258);
FORCEPROP 2 LAST CDS_LIB mstr_standard
J 0
(-7675 5250);
DISPLAY 0.723404 (-7675 5250);
PAINT MONO (-7675 5250);
DISPLAY INVISIBLE (-7675 5250);
FORCEPROP 1 LAST BODY_TYPE PLUMBING
J 2
(-7675 5300);
DISPLAY 0.872340 (-7675 5300);
PAINT GREEN (-7675 5300);
DISPLAY INVISIBLE (-7675 5300);
FORCEPROP 1 LAST HDL_TAP TRUE
J 2
(-8000 5125);
DISPLAY 0.872340 (-8000 5125);
DISPLAY INVISIBLE (-8000 5125);
FORCEPROP 1 LAST PATH I90
J 2
(-7673 5250);
DISPLAY 0.872340 (-7673 5250);
PAINT GREEN (-7673 5250);
DISPLAY INVISIBLE (-7673 5250);
FORCEADD TAP..1
R 2
(-7675 5300);
FORCEPROP 3 LASTPIN (-7625 5300) SIG_NAME M_I_CPU1_SA_CA<5>
J 0
(-7615 5310);
DISPLAY 0.659574 (-7615 5310);
PAINT MONO (-7615 5310);
DISPLAY INVISIBLE (-7615 5310);
FORCEPROP 1 LASTPIN (-7625 5300) BN 5
J 2
(-7613 5308);
DISPLAY 0.489362 (-7613 5308);
PAINT GREEN (-7613 5308);
FORCEPROP 2 LAST CDS_LIB mstr_standard
J 0
(-7675 5300);
DISPLAY 0.723404 (-7675 5300);
PAINT MONO (-7675 5300);
DISPLAY INVISIBLE (-7675 5300);
FORCEPROP 1 LAST BODY_TYPE PLUMBING
J 2
(-7675 5350);
DISPLAY 0.872340 (-7675 5350);
PAINT GREEN (-7675 5350);
DISPLAY INVISIBLE (-7675 5350);
FORCEPROP 1 LAST HDL_TAP TRUE
J 2
(-8000 5175);
DISPLAY 0.872340 (-8000 5175);
DISPLAY INVISIBLE (-8000 5175);
FORCEPROP 1 LAST PATH I91
J 2
(-7673 5300);
DISPLAY 0.872340 (-7673 5300);
PAINT GREEN (-7673 5300);
DISPLAY INVISIBLE (-7673 5300);
FORCEADD TAP..1
R 2
(-7675 5350);
FORCEPROP 3 LASTPIN (-7625 5350) SIG_NAME M_I_CPU1_SA_CA<6>
J 0
(-7615 5360);
DISPLAY 0.659574 (-7615 5360);
PAINT MONO (-7615 5360);
DISPLAY INVISIBLE (-7615 5360);
FORCEPROP 1 LASTPIN (-7625 5350) BN 6
J 2
(-7613 5358);
DISPLAY 0.489362 (-7613 5358);
PAINT GREEN (-7613 5358);
FORCEPROP 2 LAST CDS_LIB mstr_standard
J 0
(-7675 5350);
DISPLAY 0.723404 (-7675 5350);
PAINT MONO (-7675 5350);
DISPLAY INVISIBLE (-7675 5350);
FORCEPROP 1 LAST BODY_TYPE PLUMBING
J 2
(-7675 5400);
DISPLAY 0.872340 (-7675 5400);
PAINT GREEN (-7675 5400);
DISPLAY INVISIBLE (-7675 5400);
FORCEPROP 1 LAST HDL_TAP TRUE
J 2
(-8000 5225);
DISPLAY 0.872340 (-8000 5225);
DISPLAY INVISIBLE (-8000 5225);
FORCEPROP 1 LAST PATH I92
J 2
(-7673 5350);
DISPLAY 0.872340 (-7673 5350);
PAINT GREEN (-7673 5350);
DISPLAY INVISIBLE (-7673 5350);
FORCEADD TAP..1
(-5975 3800);
FORCEPROP 3 LASTPIN (-6025 3800) SIG_NAME M_I_CPU1_SA_DQ<0>
J 0
(-6015 3810);
DISPLAY 0.659574 (-6015 3810);
PAINT MONO (-6015 3810);
DISPLAY INVISIBLE (-6015 3810);
FORCEPROP 1 LASTPIN (-6025 3800) BN 0
J 0
(-6037 3808);
DISPLAY 0.489362 (-6037 3808);
PAINT GREEN (-6037 3808);
FORCEPROP 2 LAST CDS_LIB mstr_standard
J 0
(-5975 3800);
DISPLAY 0.723404 (-5975 3800);
PAINT MONO (-5975 3800);
DISPLAY INVISIBLE (-5975 3800);
FORCEPROP 1 LAST BODY_TYPE PLUMBING
J 0
(-5975 3850);
DISPLAY 0.872340 (-5975 3850);
PAINT GREEN (-5975 3850);
DISPLAY INVISIBLE (-5975 3850);
FORCEPROP 1 LAST HDL_TAP TRUE
J 0
(-5650 3675);
DISPLAY 0.872340 (-5650 3675);
DISPLAY INVISIBLE (-5650 3675);
FORCEPROP 1 LAST PATH I93
J 0
(-5977 3800);
DISPLAY 0.872340 (-5977 3800);
PAINT GREEN (-5977 3800);
DISPLAY INVISIBLE (-5977 3800);
FORCEADD TAP..1
(-5975 3900);
FORCEPROP 3 LASTPIN (-6025 3900) SIG_NAME M_I_CPU1_SA_DQ<2>
J 0
(-6015 3910);
DISPLAY 0.659574 (-6015 3910);
PAINT MONO (-6015 3910);
DISPLAY INVISIBLE (-6015 3910);
FORCEPROP 1 LASTPIN (-6025 3900) BN 2
J 0
(-6037 3908);
DISPLAY 0.489362 (-6037 3908);
PAINT GREEN (-6037 3908);
FORCEPROP 2 LAST CDS_LIB mstr_standard
J 0
(-5975 3900);
DISPLAY 0.723404 (-5975 3900);
PAINT MONO (-5975 3900);
DISPLAY INVISIBLE (-5975 3900);
FORCEPROP 1 LAST BODY_TYPE PLUMBING
J 0
(-5975 3950);
DISPLAY 0.872340 (-5975 3950);
PAINT GREEN (-5975 3950);
DISPLAY INVISIBLE (-5975 3950);
FORCEPROP 1 LAST HDL_TAP TRUE
J 0
(-5650 3775);
DISPLAY 0.872340 (-5650 3775);
DISPLAY INVISIBLE (-5650 3775);
FORCEPROP 1 LAST PATH I94
J 0
(-5977 3900);
DISPLAY 0.872340 (-5977 3900);
PAINT GREEN (-5977 3900);
DISPLAY INVISIBLE (-5977 3900);
FORCEADD TAP..1
(-5975 3850);
FORCEPROP 3 LASTPIN (-6025 3850) SIG_NAME M_I_CPU1_SA_DQ<1>
J 0
(-6015 3860);
DISPLAY 0.659574 (-6015 3860);
PAINT MONO (-6015 3860);
DISPLAY INVISIBLE (-6015 3860);
FORCEPROP 1 LASTPIN (-6025 3850) BN 1
J 0
(-6037 3858);
DISPLAY 0.489362 (-6037 3858);
PAINT GREEN (-6037 3858);
FORCEPROP 2 LAST CDS_LIB mstr_standard
J 0
(-5975 3850);
DISPLAY 0.723404 (-5975 3850);
PAINT MONO (-5975 3850);
DISPLAY INVISIBLE (-5975 3850);
FORCEPROP 1 LAST BODY_TYPE PLUMBING
J 0
(-5975 3900);
DISPLAY 0.872340 (-5975 3900);
PAINT GREEN (-5975 3900);
DISPLAY INVISIBLE (-5975 3900);
FORCEPROP 1 LAST HDL_TAP TRUE
J 0
(-5650 3725);
DISPLAY 0.872340 (-5650 3725);
DISPLAY INVISIBLE (-5650 3725);
FORCEPROP 1 LAST PATH I95
J 0
(-5977 3850);
DISPLAY 0.872340 (-5977 3850);
PAINT GREEN (-5977 3850);
DISPLAY INVISIBLE (-5977 3850);
FORCEADD TAP..1
(-5975 3950);
FORCEPROP 3 LASTPIN (-6025 3950) SIG_NAME M_I_CPU1_SA_DQ<3>
J 0
(-6015 3960);
DISPLAY 0.659574 (-6015 3960);
PAINT MONO (-6015 3960);
DISPLAY INVISIBLE (-6015 3960);
FORCEPROP 1 LASTPIN (-6025 3950) BN 3
J 0
(-6037 3958);
DISPLAY 0.489362 (-6037 3958);
PAINT GREEN (-6037 3958);
FORCEPROP 2 LAST CDS_LIB mstr_standard
J 0
(-5975 3950);
DISPLAY 0.723404 (-5975 3950);
PAINT MONO (-5975 3950);
DISPLAY INVISIBLE (-5975 3950);
FORCEPROP 1 LAST BODY_TYPE PLUMBING
J 0
(-5975 4000);
DISPLAY 0.872340 (-5975 4000);
PAINT GREEN (-5975 4000);
DISPLAY INVISIBLE (-5975 4000);
FORCEPROP 1 LAST HDL_TAP TRUE
J 0
(-5650 3825);
DISPLAY 0.872340 (-5650 3825);
DISPLAY INVISIBLE (-5650 3825);
FORCEPROP 1 LAST PATH I96
J 0
(-5977 3950);
DISPLAY 0.872340 (-5977 3950);
PAINT GREEN (-5977 3950);
DISPLAY INVISIBLE (-5977 3950);
FORCEADD TAP..1
(-5975 4000);
FORCEPROP 3 LASTPIN (-6025 4000) SIG_NAME M_I_CPU1_SA_DQ<4>
J 0
(-6015 4010);
DISPLAY 0.659574 (-6015 4010);
PAINT MONO (-6015 4010);
DISPLAY INVISIBLE (-6015 4010);
FORCEPROP 1 LASTPIN (-6025 4000) BN 4
J 0
(-6037 4008);
DISPLAY 0.489362 (-6037 4008);
PAINT GREEN (-6037 4008);
FORCEPROP 2 LAST CDS_LIB mstr_standard
J 0
(-5975 4000);
DISPLAY 0.723404 (-5975 4000);
PAINT MONO (-5975 4000);
DISPLAY INVISIBLE (-5975 4000);
FORCEPROP 1 LAST BODY_TYPE PLUMBING
J 0
(-5975 4050);
DISPLAY 0.872340 (-5975 4050);
PAINT GREEN (-5975 4050);
DISPLAY INVISIBLE (-5975 4050);
FORCEPROP 1 LAST HDL_TAP TRUE
J 0
(-5650 3875);
DISPLAY 0.872340 (-5650 3875);
DISPLAY INVISIBLE (-5650 3875);
FORCEPROP 1 LAST PATH I97
J 0
(-5977 4000);
DISPLAY 0.872340 (-5977 4000);
PAINT GREEN (-5977 4000);
DISPLAY INVISIBLE (-5977 4000);
FORCEADD TAP..1
(-5975 4050);
FORCEPROP 3 LASTPIN (-6025 4050) SIG_NAME M_I_CPU1_SA_DQ<5>
J 0
(-6015 4060);
DISPLAY 0.659574 (-6015 4060);
PAINT MONO (-6015 4060);
DISPLAY INVISIBLE (-6015 4060);
FORCEPROP 1 LASTPIN (-6025 4050) BN 5
J 0
(-6037 4058);
DISPLAY 0.489362 (-6037 4058);
PAINT GREEN (-6037 4058);
FORCEPROP 2 LAST CDS_LIB mstr_standard
J 0
(-5975 4050);
DISPLAY 0.723404 (-5975 4050);
PAINT MONO (-5975 4050);
DISPLAY INVISIBLE (-5975 4050);
FORCEPROP 1 LAST BODY_TYPE PLUMBING
J 0
(-5975 4100);
DISPLAY 0.872340 (-5975 4100);
PAINT GREEN (-5975 4100);
DISPLAY INVISIBLE (-5975 4100);
FORCEPROP 1 LAST HDL_TAP TRUE
J 0
(-5650 3925);
DISPLAY 0.872340 (-5650 3925);
DISPLAY INVISIBLE (-5650 3925);
FORCEPROP 1 LAST PATH I98
J 0
(-5977 4050);
DISPLAY 0.872340 (-5977 4050);
PAINT GREEN (-5977 4050);
DISPLAY INVISIBLE (-5977 4050);
FORCEADD TAP..1
(-5975 4100);
FORCEPROP 3 LASTPIN (-6025 4100) SIG_NAME M_I_CPU1_SA_DQ<6>
J 0
(-6015 4110);
DISPLAY 0.659574 (-6015 4110);
PAINT MONO (-6015 4110);
DISPLAY INVISIBLE (-6015 4110);
FORCEPROP 1 LASTPIN (-6025 4100) BN 6
J 0
(-6037 4108);
DISPLAY 0.489362 (-6037 4108);
PAINT GREEN (-6037 4108);
FORCEPROP 2 LAST CDS_LIB mstr_standard
J 0
(-5975 4100);
DISPLAY 0.723404 (-5975 4100);
PAINT MONO (-5975 4100);
DISPLAY INVISIBLE (-5975 4100);
FORCEPROP 1 LAST BODY_TYPE PLUMBING
J 0
(-5975 4150);
DISPLAY 0.872340 (-5975 4150);
PAINT GREEN (-5975 4150);
DISPLAY INVISIBLE (-5975 4150);
FORCEPROP 1 LAST HDL_TAP TRUE
J 0
(-5650 3975);
DISPLAY 0.872340 (-5650 3975);
DISPLAY INVISIBLE (-5650 3975);
FORCEPROP 1 LAST PATH I99
J 0
(-5977 4100);
DISPLAY 0.872340 (-5977 4100);
PAINT GREEN (-5977 4100);
DISPLAY INVISIBLE (-5977 4100);
FORCEADD QUANTA_TITLE_BLOCK_C..1
(0 0);
FORCEPROP 0 LAST CDS_CON_LAST_MODIFIED Fri Mar 11 14:53:07 2022
J 0
(-1885 15);
DISPLAY INVISIBLE (-1885 15);
FORCEPROP 1 LAST CUSTOM_TXT_CDS <CON_LAST_MODIFIED>
J 0
(-1885 15);
DISPLAY 0.978723 (-1885 15);
FORCEPROP 2 LAST CUSTOM_TXT_CDS <XR_PAGE_TITLE>
J 0
(-7890 5250);
DISPLAY 0.638298 (-7890 5250);
PAINT PINK (-7890 5250);
DISPLAY INVISIBLE (-7890 5250);
FORCEPROP 1 LAST CUSTOM_TXT_CDS <NAME_2>
J 0
(-3175 50);
FORCEPROP 1 LAST CUSTOM_TXT_CDS <NAME_1>
J 0
(-3175 175);
FORCEPROP 1 LAST CUSTOM_TXT_CDS <Q_NUMBER>
J 0
(-1403 103);
DISPLAY 1.212766 (-1403 103);
FORCEPROP 1 LAST CUSTOM_TXT_CDS <Q_PROJ>
J 0
(-2382 102);
DISPLAY 1.212766 (-2382 102);
FORCEPROP 1 LAST CUSTOM_TXT_CDS <Q_REV>
J 0
(-184 103);
DISPLAY 1.212766 (-184 103);
FORCEPROP 1 LAST CUSTOM_TXT_CDS <CON_PAGE_NUM> OF <CON_TOTAL_PAGES>
J 0
(-446 18);
DISPLAY 0.978723 (-446 18);
FORCEPROP 1 LAST Q_TITLE DDR5 - CPU1 CHI
J 0
(-9366 26);
DISPLAY 2.446809 (-9366 26);
PAINT GREEN (-9366 26);
FORCEPROP 1 LAST Q_DEPT BU9
J 1
(-3763 49);
DISPLAY 1.957447 (-3763 49);
PAINT GREEN (-3763 49);
FORCEPROP 2 LAST PAGE_BORDER TRUE
J 0
(-7890 5250);
DISPLAY 0.638298 (-7890 5250);
PAINT PINK (-7890 5250);
DISPLAY INVISIBLE (-7890 5250);
FORCEPROP 1 LAST CDS_LMAN_SYM_OUTLINE -9475,6775,100,-125
J 0
(0 0);
DISPLAY 0.468085 (0 0);
PAINT GREEN (0 0);
DISPLAY INVISIBLE (0 0);
FORCEPROP 2 LAST CDS_LIB pure_quanta
J 0
(0 0);
DISPLAY INVISIBLE (0 0);
FORCEPROP 1 LAST COMMENT_BODY TRUE
J 0
(12 -13);
DISPLAY 0.978723 (12 -13);
PAINT GREEN (12 -13);
DISPLAY INVISIBLE (12 -13);
FORCEPROP 2 LAST CDS_XR_PAGE_TITLE CR-105 : @T6G_MB_LIB.T6G(SCH_1):PAGE105
J 0
(-7890 5250);
DISPLAY 0.638298 (-7890 5250);
PAINT PINK (-7890 5250);
DISPLAY INVISIBLE (-7890 5250);
FORCEADD DNS..2
(-8325 2250);
PAINT RED (-8325 2250);
FORCEPROP 2 LAST CDS_LIB mstr_misc
J 0
(-8325 2250);
DISPLAY INVISIBLE (-8325 2250);
FORCEPROP 1 LAST COMMENT_BODY TRUE
R 1
J 0
(-8250 2025);
DISPLAY 0.872340 (-8250 2025);
PAINT PEACH (-8250 2025);
DISPLAY INVISIBLE (-8250 2025);
WIRE 17 -1 (-7725 3975)(-7725 4000);
WIRE 17 -1 (-7725 3975)(-7725 3925);
WIRE 17 -1 (-7725 4000)(-8225 4000);
FORCEPROP 2 LAST SIG_NAME M_I_CPU1_SA_CB<7:0>
J 0
(-8175 4010);
DISPLAY 0.489362 (-8175 4010);
WIRE 17 -1 (-7725 3775)(-7725 3825);
WIRE 17 -1 (-7725 3725)(-7725 3775);
WIRE 17 -1 (-7725 3875)(-7725 3825);
WIRE 17 -1 (-7725 3875)(-7725 3925);
WIRE 17 -1 (-7725 3675)(-7725 3725);
WIRE 17 -1 (-7725 3625)(-7725 3675);
WIRE 17 -1 (-7725 3525)(-7725 3550);
WIRE 17 -1 (-7725 3525)(-7725 3475);
WIRE 17 -1 (-7725 3550)(-8225 3550);
FORCEPROP 2 LAST SIG_NAME M_I_CPU1_SB_CB<7:0>
J 0
(-8175 3560);
DISPLAY 0.489362 (-8175 3560);
WIRE 17 -1 (-7725 5075)(-7725 5125);
WIRE 17 -1 (-7725 5125)(-7725 5175);
WIRE 17 -1 (-7725 5175)(-7725 5225);
WIRE 17 -1 (-7725 5225)(-7725 5275);
WIRE 17 -1 (-7725 5275)(-7725 5325);
WIRE 17 -1 (-7725 5325)(-7725 5375);
WIRE 17 -1 (-7725 5375)(-7725 5400);
WIRE 17 -1 (-7725 5400)(-8225 5400);
FORCEPROP 2 LAST SIG_NAME M_I_CPU1_SA_CA<6:0>
J 0
(-8210 5410);
DISPLAY 0.489362 (-8210 5410);
WIRE 17 -1 (-7725 4675)(-7725 4725);
WIRE 17 -1 (-7725 4725)(-7725 4775);
WIRE 17 -1 (-7725 4775)(-7725 4825);
WIRE 17 -1 (-7725 4825)(-7725 4875);
WIRE 17 -1 (-7725 4875)(-7725 4925);
WIRE 17 -1 (-7725 4925)(-7725 4975);
WIRE 17 -1 (-7725 4975)(-7725 5000);
WIRE 17 -1 (-7725 5000)(-8225 5000);
FORCEPROP 2 LAST SIG_NAME M_I_CPU1_SB_CA<6:0>
J 0
(-8210 5010);
DISPLAY 0.489362 (-8210 5010);
WIRE 17 -1 (-7725 3425)(-7725 3475);
WIRE 17 -1 (-7725 3425)(-7725 3375);
WIRE 17 -1 (-7725 3325)(-7725 3375);
WIRE 17 -1 (-7725 3275)(-7725 3325);
WIRE 17 -1 (-7725 3225)(-7725 3275);
WIRE 17 -1 (-7725 3175)(-7725 3225);
WIRE 17 -1 (-5925 5375)(-5925 5325);
WIRE 17 -1 (-5925 5400)(-5925 5375);
WIRE 17 -1 (-5925 5325)(-5925 5275);
WIRE 17 -1 (-5925 5275)(-5925 5225);
WIRE 17 -1 (-5925 5400)(-5325 5400);
FORCEPROP 2 LAST SIG_NAME M_I_CPU1_SA_DQ<31:0>
J 0
(-5860 5410);
DISPLAY 0.489362 (-5860 5410);
WIRE 17 -1 (-5925 5225)(-5925 5175);
WIRE 17 -1 (-5925 5175)(-5925 5125);
WIRE 17 -1 (-5925 5125)(-5925 5075);
WIRE 17 -1 (-5925 5075)(-5925 5025);
WIRE 17 -1 (-5925 5025)(-5925 4975);
WIRE 17 -1 (-5925 4975)(-5925 4925);
WIRE 17 -1 (-5925 4925)(-5925 4875);
WIRE 17 -1 (-5925 4875)(-5925 4825);
WIRE 17 -1 (-5925 4825)(-5925 4775);
WIRE 17 -1 (-5925 4775)(-5925 4725);
WIRE 17 -1 (-5925 4725)(-5925 4675);
WIRE 17 -1 (-5925 4675)(-5925 4625);
WIRE 17 -1 (-5925 4575)(-5925 4625);
WIRE 17 -1 (-5925 4525)(-5925 4575);
WIRE 17 -1 (-5925 4475)(-5925 4525);
WIRE 17 -1 (-5925 4425)(-5925 4475);
WIRE 17 -1 (-5925 4425)(-5925 4375);
WIRE 17 -1 (-5925 4375)(-5925 4325);
WIRE 17 -1 (-5925 4325)(-5925 4275);
WIRE 17 -1 (-5925 4275)(-5925 4225);
WIRE 17 -1 (-5925 4225)(-5925 4175);
WIRE 17 -1 (-5925 4175)(-5925 4125);
WIRE 17 -1 (-5925 4125)(-5925 4075);
WIRE 17 -1 (-5925 4075)(-5925 4025);
WIRE 17 -1 (-5925 3975)(-5925 4025);
WIRE 17 -1 (-5925 3925)(-5925 3975);
WIRE 17 -1 (-5925 3875)(-5925 3925);
WIRE 17 -1 (-5925 3825)(-5925 3875);
WIRE 17 -1 (-5925 3725)(-5925 3675);
WIRE 17 -1 (-5925 3750)(-5925 3725);
WIRE 17 -1 (-5925 3675)(-5925 3625);
WIRE 17 -1 (-5925 3625)(-5925 3575);
WIRE 17 -1 (-5925 3750)(-5325 3750);
FORCEPROP 2 LAST SIG_NAME M_I_CPU1_SB_DQ<31:0>
J 0
(-5860 3760);
DISPLAY 0.489362 (-5860 3760);
WIRE 17 -1 (-5925 3575)(-5925 3525);
WIRE 17 -1 (-5925 3525)(-5925 3475);
WIRE 17 -1 (-5925 3475)(-5925 3425);
WIRE 17 -1 (-5925 3425)(-5925 3375);
WIRE 17 -1 (-5925 3375)(-5925 3325);
WIRE 17 -1 (-5925 3325)(-5925 3275);
WIRE 17 -1 (-5925 3275)(-5925 3225);
WIRE 17 -1 (-5925 3225)(-5925 3175);
WIRE 17 -1 (-5925 3175)(-5925 3125);
WIRE 17 -1 (-5925 3125)(-5925 3075);
WIRE 17 -1 (-5925 3075)(-5925 3025);
WIRE 17 -1 (-5925 3025)(-5925 2975);
WIRE 17 -1 (-5925 2925)(-5925 2975);
WIRE 17 -1 (-5925 2875)(-5925 2925);
WIRE 17 -1 (-5925 2825)(-5925 2875);
WIRE 17 -1 (-5925 2775)(-5925 2825);
WIRE 17 -1 (-5925 2775)(-5925 2725);
WIRE 17 -1 (-5925 2725)(-5925 2675);
WIRE 17 -1 (-5925 2675)(-5925 2625);
WIRE 17 -1 (-5925 2625)(-5925 2575);
WIRE 17 -1 (-5925 2575)(-5925 2525);
WIRE 17 -1 (-5925 2525)(-5925 2475);
WIRE 17 -1 (-5925 2475)(-5925 2425);
WIRE 17 -1 (-5925 2425)(-5925 2375);
WIRE 17 -1 (-5925 2325)(-5925 2375);
WIRE 17 -1 (-5925 2275)(-5925 2325);
WIRE 17 -1 (-5925 2225)(-5925 2275);
WIRE 17 -1 (-5925 2175)(-5925 2225);
WIRE 17 -1 (-3200 4175)(-3200 4075);
WIRE 17 -1 (-3200 4275)(-3200 4175);
WIRE 17 -1 (-3200 4075)(-3200 3975);
WIRE 17 -1 (-3200 3875)(-3200 3975);
WIRE 17 -1 (-3200 4375)(-3200 4275);
WIRE 17 -1 (-3200 4400)(-3200 4375);
WIRE 17 -1 (-3200 3775)(-3200 3875);
WIRE 17 -1 (-3200 3675)(-3200 3775);
WIRE 17 -1 (-3200 4400)(-2500 4400);
FORCEPROP 2 LAST SIG_NAME M_I_CPU1_SA_DQS_DN<9:0>
J 0
(-3135 4410);
DISPLAY 0.489362 (-3135 4410);
WIRE 17 -1 (-3400 4125)(-3400 4025);
WIRE 17 -1 (-3400 4225)(-3400 4125);
WIRE 17 -1 (-3400 3925)(-3400 4025);
WIRE 17 -1 (-3400 3825)(-3400 3925);
WIRE 17 -1 (-3400 4325)(-3400 4225);
WIRE 17 -1 (-3400 4425)(-3400 4325);
WIRE 17 -1 (-3400 3725)(-3400 3825);
WIRE 17 -1 (-3400 3725)(-3400 3625);
WIRE 17 -1 (-3400 4450)(-3400 4425);
WIRE 17 -1 (-3400 4450)(-2500 4450);
FORCEPROP 2 LAST SIG_NAME M_I_CPU1_SA_DQS_DP<9:0>
J 0
(-3135 4460);
DISPLAY 0.489362 (-3135 4460);
WIRE 17 -1 (-3400 3275)(-3400 3175);
WIRE 17 -1 (-3400 3375)(-3400 3275);
WIRE 17 -1 (-3400 3175)(-3400 3075);
WIRE 17 -1 (-3400 3075)(-3400 2975);
WIRE 17 -1 (-3400 3400)(-3400 3375);
WIRE 17 -1 (-3400 3400)(-2500 3400);
FORCEPROP 2 LAST SIG_NAME M_I_CPU1_SB_DQS_DP<9:0>
J 0
(-3135 3410);
DISPLAY 0.489362 (-3135 3410);
WIRE 17 -1 (-3200 3225)(-3200 3125);
WIRE 17 -1 (-3200 3325)(-3200 3225);
WIRE 17 -1 (-3200 3125)(-3200 3025);
WIRE 17 -1 (-3200 3025)(-3200 2925);
WIRE 17 -1 (-3200 3350)(-3200 3325);
WIRE 17 -1 (-3200 3350)(-2500 3350);
FORCEPROP 2 LAST SIG_NAME M_I_CPU1_SB_DQS_DN<9:0>
J 0
(-3135 3360);
DISPLAY 0.489362 (-3135 3360);
WIRE 17 -1 (-3400 2875)(-3400 2975);
WIRE 17 -1 (-3400 2775)(-3400 2875);
WIRE 17 -1 (-3400 2675)(-3400 2775);
WIRE 17 -1 (-3200 3575)(-3200 3475);
WIRE 17 -1 (-3200 3675)(-3200 3575);
WIRE 17 -1 (-3400 3625)(-3400 3525);
WIRE 17 -1 (-3200 2525)(-3200 2425);
WIRE 17 -1 (-3200 2625)(-3200 2525);
WIRE 17 -1 (-3200 2625)(-3200 2725);
WIRE 17 -1 (-3200 2725)(-3200 2825);
WIRE 17 -1 (-3200 2825)(-3200 2925);
WIRE 17 -1 (-3400 2575)(-3400 2475);
WIRE 17 -1 (-3400 2675)(-3400 2575);
WIRE 16 -1 (-6375 975)(-6375 1050);
WIRE 16 -1 (-8550 3000)(-8550 3075);
WIRE 16 -1 (-8350 2350)(-8350 2375);
WIRE 16 -1 (-7825 2625)(-8225 2625);
FORCEPROP 2 LAST SIG_NAME I3C_SPD_DDRGL_CPU1_SCL
J 0
(-8285 2635);
DISPLAY 0.489362 (-8285 2635);
WIRE 16 -1 (-7425 2750)(-7525 2750);
FORCEPROP 2 LAST SIG_NAME I3C_SPD_DDRI_CPU1_SCL
J 0
(-7910 2760);
DISPLAY 0.446809 (-7910 2760);
FORCEPROP 2 LASTPROP $XRERR UNIQUE?
J 0
(-8150 2760);
DISPLAY 0.638298 (-8150 2760);
PAINT MONO (-8150 2760);
DISPLAY INVISIBLE (-8150 2760);
WIRE 16 -1 (-7525 2750)(-7525 2625);
WIRE 16 -1 (-7525 2625)(-7625 2625);
WIRE 16 -1 (-7425 2500)(-8125 2500);
FORCEPROP 2 LAST SIG_NAME PWRGD_CHI_CPU1_DIMM
J 0
(-8035 2510);
DISPLAY 0.489362 (-8035 2510);
FORCEPROP 2 LASTPROP $XRERR UNIQUE?
J 0
(-8275 2510);
DISPLAY 0.638298 (-8275 2510);
PAINT MONO (-8275 2510);
DISPLAY INVISIBLE (-8275 2510);
WIRE 16 -1 (-8125 2100)(-8125 2500);
WIRE 16 -1 (-8125 2100)(-8350 2100);
WIRE 16 -1 (-8350 2100)(-8375 2100);
WIRE 16 -1 (-8350 2150)(-8350 2100);
WIRE 16 -1 (-7425 2350)(-8025 2350);
FORCEPROP 2 LAST SIG_NAME TP_CHI_CPU1_DIMM_RFU_5
J 0
(-8035 2360);
DISPLAY 0.489362 (-8035 2360);
FORCEPROP 2 LASTPROP $XRERR UNIQUE?
J 0
(-8265 2350);
DISPLAY 0.638298 (-8265 2350);
PAINT MONO (-8265 2350);
DISPLAY INVISIBLE (-8265 2350);
WIRE 16 -1 (-8575 2100)(-8975 2100);
FORCEPROP 2 LAST SIG_NAME PWRGD_CHGL_CPU1
J 0
(-8935 2110);
DISPLAY 0.489362 (-8935 2110);
WIRE 16 -1 (-7425 2400)(-8025 2400);
FORCEPROP 2 LAST SIG_NAME TP_CHI_CPU1_DIMM_RFU_6
J 0
(-8035 2410);
DISPLAY 0.489362 (-8035 2410);
FORCEPROP 2 LASTPROP $XRERR UNIQUE?
J 0
(-8265 2400);
DISPLAY 0.638298 (-8265 2400);
PAINT MONO (-8265 2400);
DISPLAY INVISIBLE (-8265 2400);
WIRE 16 -1 (-7425 2800)(-8225 2800);
FORCEPROP 2 LAST SIG_NAME I3C_SPD_DDRGL_CPU1_SDA
J 0
(-8235 2810);
DISPLAY 0.489362 (-8235 2810);
WIRE 16 -1 (-7425 2850)(-8225 2850);
FORCEPROP 2 LAST SIG_NAME PD_CHI_CPU1_DIMM_SAA
J 0
(-8200 2860);
DISPLAY 0.489362 (-8200 2860);
WIRE 16 -1 (-8450 2900)(-7425 2900);
WIRE 16 -1 (-8450 3300)(-8450 2900);
WIRE 16 -1 (-8450 3325)(-8450 3300);
WIRE 16 -1 (-8550 3300)(-8450 3300);
WIRE 16 -1 (-8550 3275)(-8550 3300);
WIRE 16 -1 (-2125 5150)(-1825 5150);
WIRE 16 -1 (-2125 5200)(-2125 5150);
WIRE 16 -1 (-1825 5200)(-2125 5200);
WIRE 16 -1 (-2125 5200)(-2125 5250);
WIRE 16 -1 (-1825 5250)(-2125 5250);
WIRE 16 -1 (-2125 5250)(-2125 6000);
WIRE 16 -1 (-2250 6000)(-2125 6000);
WIRE 16 -1 (-2250 6000)(-2825 6000);
WIRE 16 -1 (-2250 6000)(-2250 5900);
WIRE 16 -1 (-2825 5900)(-2825 6000);
WIRE 16 -1 (-2825 6000)(-2825 6075);
WIRE 16 -1 (-325 5250)(-325 5200);
WIRE 16 -1 (-325 5250)(-625 5250);
WIRE 16 -1 (-325 5200)(-325 5150);
WIRE 16 -1 (-325 5200)(-625 5200);
WIRE 16 -1 (-325 5150)(-625 5150);
WIRE 16 -1 (-325 5150)(-325 5100);
WIRE 16 -1 (-325 5100)(-325 5050);
WIRE 16 -1 (-325 5100)(-625 5100);
WIRE 16 -1 (-325 5050)(-325 5000);
WIRE 16 -1 (-325 5050)(-625 5050);
WIRE 16 -1 (-325 5000)(-325 4950);
WIRE 16 -1 (-325 5000)(-625 5000);
WIRE 16 -1 (-325 4950)(-325 4900);
WIRE 16 -1 (-325 4950)(-625 4950);
WIRE 16 -1 (-325 4900)(-325 4850);
WIRE 16 -1 (-325 4900)(-625 4900);
WIRE 16 -1 (-325 4850)(-325 4800);
WIRE 16 -1 (-325 4850)(-625 4850);
WIRE 16 -1 (-325 4800)(-325 4750);
WIRE 16 -1 (-325 4800)(-625 4800);
WIRE 16 -1 (-325 4750)(-325 4700);
WIRE 16 -1 (-325 4750)(-625 4750);
WIRE 16 -1 (-325 4700)(-325 4650);
WIRE 16 -1 (-325 4700)(-625 4700);
WIRE 16 -1 (-325 4650)(-325 4600);
WIRE 16 -1 (-325 4650)(-625 4650);
WIRE 16 -1 (-325 4600)(-325 4550);
WIRE 16 -1 (-325 4600)(-625 4600);
WIRE 16 -1 (-325 4550)(-325 4500);
WIRE 16 -1 (-325 4550)(-625 4550);
WIRE 16 -1 (-325 4500)(-325 4450);
WIRE 16 -1 (-325 4500)(-625 4500);
WIRE 16 -1 (-325 4450)(-325 4400);
WIRE 16 -1 (-325 4450)(-625 4450);
WIRE 16 -1 (-325 4400)(-325 4350);
WIRE 16 -1 (-325 4400)(-625 4400);
WIRE 16 -1 (-325 4350)(-325 4300);
WIRE 16 -1 (-325 4350)(-625 4350);
WIRE 16 -1 (-325 4300)(-325 4250);
WIRE 16 -1 (-325 4300)(-625 4300);
WIRE 16 -1 (-325 4250)(-325 4200);
WIRE 16 -1 (-325 4250)(-625 4250);
WIRE 16 -1 (-325 4200)(-325 4150);
WIRE 16 -1 (-325 4200)(-625 4200);
WIRE 16 -1 (-325 4150)(-325 4100);
WIRE 16 -1 (-325 4150)(-625 4150);
WIRE 16 -1 (-325 4100)(-625 4100);
WIRE 16 -1 (-325 4100)(-325 4050);
WIRE 16 -1 (-325 4050)(-325 4000);
WIRE 16 -1 (-325 4050)(-625 4050);
WIRE 16 -1 (-325 4000)(-325 3950);
WIRE 16 -1 (-325 4000)(-625 4000);
WIRE 16 -1 (-325 3950)(-325 3900);
WIRE 16 -1 (-325 3950)(-625 3950);
WIRE 16 -1 (-325 3900)(-325 3850);
WIRE 16 -1 (-325 3900)(-625 3900);
WIRE 16 -1 (-325 3850)(-325 3800);
WIRE 16 -1 (-325 3850)(-625 3850);
WIRE 16 -1 (-325 3800)(-325 3750);
WIRE 16 -1 (-325 3800)(-625 3800);
WIRE 16 -1 (-325 3750)(-325 3700);
WIRE 16 -1 (-325 3750)(-625 3750);
WIRE 16 -1 (-325 3700)(-325 3650);
WIRE 16 -1 (-325 3700)(-625 3700);
WIRE 16 -1 (-325 3650)(-325 3600);
WIRE 16 -1 (-325 3650)(-625 3650);
WIRE 16 -1 (-325 3600)(-325 3550);
WIRE 16 -1 (-325 3600)(-625 3600);
WIRE 16 -1 (-325 3550)(-325 3500);
WIRE 16 -1 (-325 3550)(-625 3550);
WIRE 16 -1 (-325 3500)(-325 3450);
WIRE 16 -1 (-325 3500)(-625 3500);
WIRE 16 -1 (-325 3450)(-325 3400);
WIRE 16 -1 (-325 3450)(-625 3450);
WIRE 16 -1 (-325 3400)(-325 3350);
WIRE 16 -1 (-325 3400)(-625 3400);
WIRE 16 -1 (-325 3350)(-325 3300);
WIRE 16 -1 (-325 3350)(-625 3350);
WIRE 16 -1 (-325 3300)(-325 3250);
WIRE 16 -1 (-325 3300)(-625 3300);
WIRE 16 -1 (-325 3250)(-325 3200);
WIRE 16 -1 (-325 3250)(-625 3250);
WIRE 16 -1 (-325 3200)(-325 3150);
WIRE 16 -1 (-325 3200)(-625 3200);
WIRE 16 -1 (-325 3150)(-325 3100);
WIRE 16 -1 (-325 3150)(-625 3150);
WIRE 16 -1 (-325 3100)(-625 3100);
WIRE 16 -1 (-325 3100)(-325 3050);
WIRE 16 -1 (-325 3050)(-325 3000);
WIRE 16 -1 (-325 3050)(-625 3050);
WIRE 16 -1 (-325 3000)(-325 2950);
WIRE 16 -1 (-325 3000)(-625 3000);
WIRE 16 -1 (-325 2950)(-325 2900);
WIRE 16 -1 (-325 2950)(-625 2950);
WIRE 16 -1 (-325 2900)(-325 2850);
WIRE 16 -1 (-325 2900)(-625 2900);
WIRE 16 -1 (-325 2850)(-325 2800);
WIRE 16 -1 (-325 2850)(-625 2850);
WIRE 16 -1 (-325 2800)(-325 2750);
WIRE 16 -1 (-325 2800)(-625 2800);
WIRE 16 -1 (-325 2750)(-325 2700);
WIRE 16 -1 (-325 2750)(-625 2750);
WIRE 16 -1 (-325 2700)(-325 2650);
WIRE 16 -1 (-325 2700)(-625 2700);
WIRE 16 -1 (-325 2650)(-325 2600);
WIRE 16 -1 (-325 2650)(-625 2650);
WIRE 16 -1 (-325 2600)(-325 2550);
WIRE 16 -1 (-325 2600)(-625 2600);
WIRE 16 -1 (-325 2550)(-325 2500);
WIRE 16 -1 (-325 2550)(-625 2550);
WIRE 16 -1 (-325 2500)(-325 2450);
WIRE 16 -1 (-325 2500)(-625 2500);
WIRE 16 -1 (-325 2450)(-325 2400);
WIRE 16 -1 (-325 2450)(-625 2450);
WIRE 16 -1 (-325 2400)(-325 2350);
WIRE 16 -1 (-325 2400)(-625 2400);
WIRE 16 -1 (-325 2350)(-325 2300);
WIRE 16 -1 (-325 2350)(-625 2350);
WIRE 16 -1 (-325 2300)(-325 2250);
WIRE 16 -1 (-325 2300)(-625 2300);
WIRE 16 -1 (-325 2250)(-325 2200);
WIRE 16 -1 (-325 2250)(-625 2250);
WIRE 16 -1 (-325 2200)(-325 2150);
WIRE 16 -1 (-325 2200)(-625 2200);
WIRE 16 -1 (-325 2150)(-325 2100);
WIRE 16 -1 (-325 2150)(-625 2150);
WIRE 16 -1 (-325 2100)(-325 2000);
WIRE 16 -1 (-325 2100)(-625 2100);
WIRE 16 -1 (-325 2000)(-325 1950);
WIRE 16 -1 (-325 2000)(-625 2000);
WIRE 16 -1 (-325 1950)(-325 1900);
WIRE 16 -1 (-325 1950)(-625 1950);
WIRE 16 -1 (-325 1900)(-325 1650);
WIRE 16 -1 (-325 1900)(-625 1900);
WIRE 16 -1 (-1825 2000)(-2125 2000);
WIRE 16 -1 (-2125 2050)(-2125 2000);
WIRE 16 -1 (-2125 2000)(-2125 1875);
WIRE 16 -1 (-1825 2050)(-2125 2050);
WIRE 16 -1 (-2125 2100)(-2125 2050);
WIRE 16 -1 (-1825 2100)(-2125 2100);
WIRE 16 -1 (-2125 2150)(-2125 2100);
WIRE 16 -1 (-1825 2150)(-2125 2150);
WIRE 16 -1 (-2125 2200)(-2125 2150);
WIRE 16 -1 (-1825 2200)(-2125 2200);
WIRE 16 -1 (-2125 2250)(-2125 2200);
WIRE 16 -1 (-1825 2250)(-2125 2250);
WIRE 16 -1 (-2125 2300)(-2125 2250);
WIRE 16 -1 (-1825 2300)(-2125 2300);
WIRE 16 -1 (-2125 2350)(-2125 2300);
WIRE 16 -1 (-1825 2350)(-2125 2350);
WIRE 16 -1 (-2125 2400)(-2125 2350);
WIRE 16 -1 (-1825 2400)(-2125 2400);
WIRE 16 -1 (-2125 2450)(-2125 2400);
WIRE 16 -1 (-1825 2450)(-2125 2450);
WIRE 16 -1 (-2125 2500)(-2125 2450);
WIRE 16 -1 (-1825 2500)(-2125 2500);
WIRE 16 -1 (-2125 2550)(-2125 2500);
WIRE 16 -1 (-1825 2550)(-2125 2550);
WIRE 16 -1 (-2125 2600)(-2125 2550);
WIRE 16 -1 (-1825 2600)(-2125 2600);
WIRE 16 -1 (-2125 2650)(-2125 2600);
WIRE 16 -1 (-1825 2650)(-2125 2650);
WIRE 16 -1 (-2125 2700)(-2125 2650);
WIRE 16 -1 (-1825 2700)(-2125 2700);
WIRE 16 -1 (-2125 2750)(-2125 2700);
WIRE 16 -1 (-1825 2750)(-2125 2750);
WIRE 16 -1 (-2125 2800)(-2125 2750);
WIRE 16 -1 (-1825 2800)(-2125 2800);
WIRE 16 -1 (-2125 2850)(-2125 2800);
WIRE 16 -1 (-1825 2850)(-2125 2850);
WIRE 16 -1 (-2125 2900)(-2125 2850);
WIRE 16 -1 (-1825 2900)(-2125 2900);
WIRE 16 -1 (-2125 2950)(-2125 2900);
WIRE 16 -1 (-1825 2950)(-2125 2950);
WIRE 16 -1 (-2125 3000)(-2125 2950);
WIRE 16 -1 (-1825 3000)(-2125 3000);
WIRE 16 -1 (-2125 3050)(-2125 3000);
WIRE 16 -1 (-1825 3050)(-2125 3050);
WIRE 16 -1 (-2125 3100)(-2125 3050);
WIRE 16 -1 (-1825 3100)(-2125 3100);
WIRE 16 -1 (-2125 3150)(-2125 3100);
WIRE 16 -1 (-1825 3150)(-2125 3150);
WIRE 16 -1 (-2125 3200)(-2125 3150);
WIRE 16 -1 (-1825 3200)(-2125 3200);
WIRE 16 -1 (-2125 3250)(-2125 3200);
WIRE 16 -1 (-1825 3250)(-2125 3250);
WIRE 16 -1 (-2125 3300)(-2125 3250);
WIRE 16 -1 (-1825 3300)(-2125 3300);
WIRE 16 -1 (-2125 3350)(-2125 3300);
WIRE 16 -1 (-1825 3350)(-2125 3350);
WIRE 16 -1 (-2125 3400)(-2125 3350);
WIRE 16 -1 (-1825 3400)(-2125 3400);
WIRE 16 -1 (-2125 3450)(-2125 3400);
WIRE 16 -1 (-1825 3450)(-2125 3450);
WIRE 16 -1 (-2125 3500)(-2125 3450);
WIRE 16 -1 (-1825 3500)(-2125 3500);
WIRE 16 -1 (-2125 3550)(-2125 3500);
WIRE 16 -1 (-1825 3550)(-2125 3550);
WIRE 16 -1 (-2125 3600)(-2125 3550);
WIRE 16 -1 (-1825 3600)(-2125 3600);
WIRE 16 -1 (-2125 3650)(-2125 3600);
WIRE 16 -1 (-1825 3650)(-2125 3650);
WIRE 16 -1 (-2125 3700)(-2125 3650);
WIRE 16 -1 (-1825 3700)(-2125 3700);
WIRE 16 -1 (-2125 3750)(-2125 3700);
WIRE 16 -1 (-1825 3750)(-2125 3750);
WIRE 16 -1 (-2125 3800)(-2125 3750);
WIRE 16 -1 (-1825 3800)(-2125 3800);
WIRE 16 -1 (-2125 3850)(-2125 3800);
WIRE 16 -1 (-1825 3850)(-2125 3850);
WIRE 16 -1 (-2125 3900)(-2125 3850);
WIRE 16 -1 (-1825 3900)(-2125 3900);
WIRE 16 -1 (-2125 3950)(-2125 3900);
WIRE 16 -1 (-1825 3950)(-2125 3950);
WIRE 16 -1 (-2125 4000)(-2125 3950);
WIRE 16 -1 (-1825 4000)(-2125 4000);
WIRE 16 -1 (-2125 4050)(-2125 4000);
WIRE 16 -1 (-2125 4100)(-2125 4050);
WIRE 16 -1 (-1825 4050)(-2125 4050);
WIRE 16 -1 (-1825 4100)(-2125 4100);
WIRE 16 -1 (-2125 4150)(-2125 4100);
WIRE 16 -1 (-1825 4150)(-2125 4150);
WIRE 16 -1 (-2125 4200)(-2125 4150);
WIRE 16 -1 (-1825 4200)(-2125 4200);
WIRE 16 -1 (-2125 4250)(-2125 4200);
WIRE 16 -1 (-1825 4250)(-2125 4250);
WIRE 16 -1 (-2125 4300)(-2125 4250);
WIRE 16 -1 (-1825 4300)(-2125 4300);
WIRE 16 -1 (-2125 4350)(-2125 4300);
WIRE 16 -1 (-1825 4350)(-2125 4350);
WIRE 16 -1 (-2125 4400)(-2125 4350);
WIRE 16 -1 (-1825 4400)(-2125 4400);
WIRE 16 -1 (-2125 4450)(-2125 4400);
WIRE 16 -1 (-1825 4450)(-2125 4450);
WIRE 16 -1 (-2125 4500)(-2125 4450);
WIRE 16 -1 (-1825 4500)(-2125 4500);
WIRE 16 -1 (-2125 4550)(-2125 4500);
WIRE 16 -1 (-1825 4550)(-2125 4550);
WIRE 16 -1 (-2125 4600)(-2125 4550);
WIRE 16 -1 (-1825 4600)(-2125 4600);
WIRE 16 -1 (-2125 4650)(-2125 4600);
WIRE 16 -1 (-1825 4650)(-2125 4650);
WIRE 16 -1 (-2125 4700)(-2125 4650);
WIRE 16 -1 (-1825 4700)(-2125 4700);
WIRE 16 -1 (-2125 4750)(-2125 4700);
WIRE 16 -1 (-1825 4750)(-2125 4750);
WIRE 16 -1 (-2125 4800)(-2125 4750);
WIRE 16 -1 (-1825 4800)(-2125 4800);
WIRE 16 -1 (-2125 4850)(-2125 4800);
WIRE 16 -1 (-1825 4850)(-2125 4850);
WIRE 16 -1 (-2125 4900)(-2125 4850);
WIRE 16 -1 (-1825 4900)(-2125 4900);
WIRE 16 -1 (-2125 4950)(-2125 4900);
WIRE 16 -1 (-1825 4950)(-2125 4950);
WIRE 16 -1 (-2125 5000)(-2125 4950);
WIRE 16 -1 (-1825 5000)(-2125 5000);
WIRE 16 -1 (-2125 5050)(-2125 5000);
WIRE 16 -1 (-1825 5050)(-2125 5050);
WIRE 16 -1 (-2125 5100)(-2125 5050);
WIRE 16 -1 (-1825 5100)(-2125 5100);
WIRE 16 -1 (-3650 3350)(-3500 3350);
WIRE 16 -1 (-3650 3300)(-3300 3300);
WIRE 16 -1 (-3650 4400)(-3500 4400);
WIRE 16 -1 (-3650 4350)(-3300 4350);
WIRE 16 -1 (-3500 4300)(-3650 4300);
WIRE 16 -1 (-3650 4250)(-3300 4250);
WIRE 16 -1 (-3650 3100)(-3300 3100);
WIRE 16 -1 (-3500 4200)(-3650 4200);
WIRE 16 -1 (-3500 3050)(-3650 3050);
WIRE 16 -1 (-3650 3000)(-3300 3000);
WIRE 16 -1 (-3650 4050)(-3300 4050);
WIRE 16 -1 (-3650 2950)(-3500 2950);
WIRE 16 -1 (-3650 2900)(-3300 2900);
WIRE 16 -1 (-3650 4000)(-3500 4000);
WIRE 16 -1 (-3300 3950)(-3650 3950);
WIRE 16 -1 (-3500 2850)(-3650 2850);
WIRE 16 -1 (-3650 2800)(-3300 2800);
WIRE 16 -1 (-3500 3900)(-3650 3900);
WIRE 16 -1 (-3650 3850)(-3300 3850);
WIRE 16 -1 (-3500 2750)(-3650 2750);
WIRE 16 -1 (-3650 2700)(-3300 2700);
WIRE 16 -1 (-3500 3800)(-3650 3800);
WIRE 16 -1 (-3650 3750)(-3300 3750);
WIRE 16 -1 (-3500 2650)(-3650 2650);
WIRE 16 -1 (-3650 2600)(-3300 2600);
WIRE 16 -1 (-3500 3700)(-3650 3700);
WIRE 16 -1 (-3650 3650)(-3300 3650);
WIRE 16 -1 (-3650 2550)(-3500 2550);
WIRE 16 -1 (-3650 2500)(-3300 2500);
WIRE 16 -1 (-3650 3600)(-3500 3600);
WIRE 16 -1 (-3650 3550)(-3300 3550);
WIRE 16 -1 (-3500 2450)(-3650 2450);
WIRE 16 -1 (-3650 2400)(-3300 2400);
WIRE 16 -1 (-3500 3500)(-3650 3500);
WIRE 16 -1 (-3650 3450)(-3300 3450);
WIRE 16 -1 (-3500 3150)(-3650 3150);
WIRE 16 -1 (-3650 3200)(-3300 3200);
WIRE 16 -1 (-3500 3250)(-3650 3250);
WIRE 16 -1 (-3500 4100)(-3650 4100);
WIRE 16 -1 (-3300 4150)(-3650 4150);
WIRE 16 -1 (-6225 5350)(-6025 5350);
WIRE 16 -1 (-7425 2100)(-8025 2100);
FORCEPROP 2 LAST SIG_NAME TP_CHI_CPU1_DIMM_RFU_0
J 0
(-8035 2110);
DISPLAY 0.489362 (-8035 2110);
FORCEPROP 2 LASTPROP $XRERR UNIQUE?
J 0
(-8265 2100);
DISPLAY 0.638298 (-8265 2100);
PAINT MONO (-8265 2100);
DISPLAY INVISIBLE (-8265 2100);
WIRE 16 -1 (-7425 2150)(-8025 2150);
FORCEPROP 2 LAST SIG_NAME TP_CHI_CPU1_DIMM_RFU_1
J 0
(-8035 2160);
DISPLAY 0.489362 (-8035 2160);
FORCEPROP 2 LASTPROP $XRERR UNIQUE?
J 0
(-8265 2150);
DISPLAY 0.638298 (-8265 2150);
PAINT MONO (-8265 2150);
DISPLAY INVISIBLE (-8265 2150);
WIRE 16 -1 (-7425 2200)(-8025 2200);
FORCEPROP 2 LAST SIG_NAME TP_CHI_CPU1_DIMM_RFU_2
J 0
(-8035 2210);
DISPLAY 0.489362 (-8035 2210);
FORCEPROP 2 LASTPROP $XRERR UNIQUE?
J 0
(-8265 2200);
DISPLAY 0.638298 (-8265 2200);
PAINT MONO (-8265 2200);
DISPLAY INVISIBLE (-8265 2200);
WIRE 16 -1 (-7425 2250)(-8025 2250);
FORCEPROP 2 LAST SIG_NAME TP_CHI_CPU1_DIMM_RFU_3
J 0
(-8035 2260);
DISPLAY 0.489362 (-8035 2260);
FORCEPROP 2 LASTPROP $XRERR UNIQUE?
J 0
(-8265 2250);
DISPLAY 0.638298 (-8265 2250);
PAINT MONO (-8265 2250);
DISPLAY INVISIBLE (-8265 2250);
WIRE 16 -1 (-7425 2300)(-8025 2300);
FORCEPROP 2 LAST SIG_NAME TP_CHI_CPU1_DIMM_RFU_4
J 0
(-8035 2310);
DISPLAY 0.489362 (-8035 2310);
FORCEPROP 2 LASTPROP $XRERR UNIQUE?
J 0
(-8265 2300);
DISPLAY 0.638298 (-8265 2300);
PAINT MONO (-8265 2300);
DISPLAY INVISIBLE (-8265 2300);
WIRE 16 -1 (-7425 3050)(-8075 3050);
FORCEPROP 2 LAST SIG_NAME M_I_CPU1_RESET_N
J 0
(-8060 3060);
DISPLAY 0.489362 (-8060 3060);
WIRE 16 -1 (-7425 4500)(-8225 4500);
FORCEPROP 2 LAST SIG_NAME M_I_CPU1_SB_PAR
J 0
(-8175 4510);
DISPLAY 0.489362 (-8175 4510);
WIRE 16 -1 (-7425 4550)(-8225 4550);
FORCEPROP 2 LAST SIG_NAME M_I_CPU1_SA_PAR
J 0
(-8175 4560);
DISPLAY 0.489362 (-8175 4560);
WIRE 16 -1 (-7425 1900)(-8225 1900);
FORCEPROP 2 LAST SIG_NAME M_I_CPU1_SB_RSP<0>
J 0
(-8175 1910);
DISPLAY 0.489362 (-8175 1910);
WIRE 16 -1 (-7425 1950)(-8225 1950);
FORCEPROP 2 LAST SIG_NAME M_I_CPU1_SA_RSP<0>
J 0
(-8175 1960);
DISPLAY 0.489362 (-8175 1960);
WIRE 16 -1 (-6025 2150)(-6225 2150);
WIRE 16 -1 (-6025 2200)(-6225 2200);
WIRE 16 -1 (-6025 2250)(-6225 2250);
WIRE 16 -1 (-6225 2300)(-6025 2300);
WIRE 16 -1 (-6025 2350)(-6225 2350);
WIRE 16 -1 (-6025 2400)(-6225 2400);
WIRE 16 -1 (-6025 2450)(-6225 2450);
WIRE 16 -1 (-6225 2500)(-6025 2500);
WIRE 16 -1 (-6025 2550)(-6225 2550);
WIRE 16 -1 (-6025 2600)(-6225 2600);
WIRE 16 -1 (-6025 2650)(-6225 2650);
WIRE 16 -1 (-6225 2700)(-6025 2700);
WIRE 16 -1 (-6025 2750)(-6225 2750);
WIRE 16 -1 (-6025 2800)(-6225 2800);
WIRE 16 -1 (-6025 2850)(-6225 2850);
WIRE 16 -1 (-6225 2900)(-6025 2900);
WIRE 16 -1 (-6025 2950)(-6225 2950);
WIRE 16 -1 (-6025 3000)(-6225 3000);
WIRE 16 -1 (-6025 3050)(-6225 3050);
WIRE 16 -1 (-6225 3100)(-6025 3100);
WIRE 16 -1 (-6025 3150)(-6225 3150);
WIRE 16 -1 (-6025 3200)(-6225 3200);
WIRE 16 -1 (-6025 3250)(-6225 3250);
WIRE 16 -1 (-6225 3300)(-6025 3300);
WIRE 16 -1 (-6025 3350)(-6225 3350);
WIRE 16 -1 (-6025 3400)(-6225 3400);
WIRE 16 -1 (-6025 3450)(-6225 3450);
WIRE 16 -1 (-6225 3500)(-6025 3500);
WIRE 16 -1 (-6025 3550)(-6225 3550);
WIRE 16 -1 (-6025 3600)(-6225 3600);
WIRE 16 -1 (-6025 3650)(-6225 3650);
WIRE 16 -1 (-6225 3700)(-6025 3700);
WIRE 16 -1 (-6025 3800)(-6225 3800);
WIRE 16 -1 (-6025 3850)(-6225 3850);
WIRE 16 -1 (-6025 3900)(-6225 3900);
WIRE 16 -1 (-6225 3950)(-6025 3950);
WIRE 16 -1 (-6025 4000)(-6225 4000);
WIRE 16 -1 (-6025 4050)(-6225 4050);
WIRE 16 -1 (-6025 4100)(-6225 4100);
WIRE 16 -1 (-6225 4150)(-6025 4150);
WIRE 16 -1 (-6025 4200)(-6225 4200);
WIRE 16 -1 (-6025 4250)(-6225 4250);
WIRE 16 -1 (-6025 4300)(-6225 4300);
WIRE 16 -1 (-6225 4350)(-6025 4350);
WIRE 16 -1 (-6025 4400)(-6225 4400);
WIRE 16 -1 (-6025 4450)(-6225 4450);
WIRE 16 -1 (-6025 4500)(-6225 4500);
WIRE 16 -1 (-6225 4550)(-6025 4550);
WIRE 16 -1 (-6025 4600)(-6225 4600);
WIRE 16 -1 (-6025 4650)(-6225 4650);
WIRE 16 -1 (-6025 4700)(-6225 4700);
WIRE 16 -1 (-6225 4750)(-6025 4750);
WIRE 16 -1 (-6025 4800)(-6225 4800);
WIRE 16 -1 (-6025 4850)(-6225 4850);
WIRE 16 -1 (-6025 4900)(-6225 4900);
WIRE 16 -1 (-6225 4950)(-6025 4950);
WIRE 16 -1 (-6025 5000)(-6225 5000);
WIRE 16 -1 (-6025 5050)(-6225 5050);
WIRE 16 -1 (-6025 5100)(-6225 5100);
WIRE 16 -1 (-6225 5150)(-6025 5150);
WIRE 16 -1 (-6025 5200)(-6225 5200);
WIRE 16 -1 (-6025 5250)(-6225 5250);
WIRE 16 -1 (-6025 5300)(-6225 5300);
WIRE 16 -1 (-7425 4250)(-8225 4250);
FORCEPROP 2 LAST SIG_NAME M_I_CPU1_SB_CS_N<1>
J 0
(-8175 4260);
DISPLAY 0.489362 (-8175 4260);
WIRE 16 -1 (-7425 4400)(-8225 4400);
FORCEPROP 2 LAST SIG_NAME M_I_CPU1_SA_CS_N<1>
J 0
(-8175 4410);
DISPLAY 0.489362 (-8175 4410);
WIRE 16 -1 (-7425 4200)(-8225 4200);
FORCEPROP 2 LAST SIG_NAME M_I_CPU1_SB_CS_N<0>
J 0
(-8175 4210);
DISPLAY 0.489362 (-8175 4210);
WIRE 16 -1 (-7425 4350)(-8225 4350);
FORCEPROP 2 LAST SIG_NAME M_I_CPU1_SA_CS_N<0>
J 0
(-8175 4360);
DISPLAY 0.489362 (-8175 4360);
WIRE 16 -1 (-7425 4100)(-8225 4100);
FORCEPROP 2 LAST SIG_NAME M_I_CPU1_CLK_DP<0>
J 0
(-8175 4110);
DISPLAY 0.489362 (-8175 4110);
WIRE 16 -1 (-7425 4050)(-8225 4050);
FORCEPROP 2 LAST SIG_NAME M_I_CPU1_CLK_DN<0>
J 0
(-8175 4060);
DISPLAY 0.489362 (-8175 4060);
WIRE 16 -1 (-7425 3150)(-7625 3150);
WIRE 16 -1 (-7425 3200)(-7625 3200);
WIRE 16 -1 (-7425 3250)(-7625 3250);
WIRE 16 -1 (-7425 3300)(-7625 3300);
WIRE 16 -1 (-7425 3350)(-7625 3350);
WIRE 16 -1 (-7425 3400)(-7625 3400);
WIRE 16 -1 (-7425 3450)(-7625 3450);
WIRE 16 -1 (-7425 3600)(-7625 3600);
WIRE 16 -1 (-7425 3700)(-7625 3700);
WIRE 16 -1 (-7425 3750)(-7625 3750);
WIRE 16 -1 (-7425 3850)(-7625 3850);
WIRE 16 -1 (-7425 3900)(-7625 3900);
WIRE 16 -1 (-7425 4950)(-7625 4950);
WIRE 16 -1 (-7425 5350)(-7625 5350);
WIRE 16 -1 (-7425 4900)(-7625 4900);
WIRE 16 -1 (-7425 5300)(-7625 5300);
WIRE 16 -1 (-7425 4850)(-7625 4850);
WIRE 16 -1 (-7425 5250)(-7625 5250);
WIRE 16 -1 (-7425 4800)(-7625 4800);
WIRE 16 -1 (-7425 5200)(-7625 5200);
WIRE 16 -1 (-7425 4750)(-7625 4750);
WIRE 16 -1 (-7425 5150)(-7625 5150);
WIRE 16 -1 (-7425 4700)(-7625 4700);
WIRE 16 -1 (-7425 5100)(-7625 5100);
WIRE 16 -1 (-7425 4650)(-7625 4650);
WIRE 16 -1 (-7425 5050)(-7625 5050);
WIRE 16 -1 (-7425 3000)(-8075 3000);
FORCEPROP 2 LAST SIG_NAME M_I_CPU1_ALERT_N
J 0
(-8060 3010);
DISPLAY 0.489362 (-8060 3010);
WIRE 16 -1 (-7425 3500)(-7625 3500);
WIRE 16 -1 (-7425 3650)(-7625 3650);
WIRE 16 -1 (-7425 3800)(-7625 3800);
WIRE 16 -1 (-7425 3950)(-7625 3950);
WIRE 16 -1 (-2250 5575)(-2825 5575);
WIRE 16 -1 (-2250 5575)(-2250 5700);
WIRE 16 -1 (-2825 5575)(-2825 5700);
WIRE 16 -1 (-2825 5575)(-2825 5500);
WIRE 16 -1 (-6375 1325)(-6375 1250);
WIRE 16 -1 (-6375 1325)(-7100 1325);
FORCEPROP 2 LAST SIG_NAME PD_CHI_CPU1_DIMM_SAA
J 0
(-7085 1335);
DISPLAY 0.489362 (-7085 1335);
DOT 1 (-325 5200);
DOT 1 (-325 5150);
DOT 1 (-325 5100);
DOT 1 (-325 5050);
DOT 1 (-325 5000);
DOT 1 (-325 4950);
DOT 1 (-325 4900);
DOT 1 (-325 4850);
DOT 1 (-325 4800);
DOT 1 (-325 4750);
DOT 1 (-325 4700);
DOT 1 (-325 4650);
DOT 1 (-325 4550);
DOT 1 (-325 4600);
DOT 1 (-325 4500);
DOT 1 (-325 4400);
DOT 1 (-325 4450);
DOT 1 (-325 4300);
DOT 1 (-325 4350);
DOT 1 (-325 4250);
DOT 1 (-325 4200);
DOT 1 (-325 4150);
DOT 1 (-325 4050);
DOT 1 (-325 4100);
DOT 1 (-325 4000);
DOT 1 (-325 3950);
DOT 1 (-325 3900);
DOT 1 (-325 3850);
DOT 1 (-325 3800);
DOT 1 (-2125 5200);
DOT 1 (-2125 5250);
DOT 1 (-2125 5050);
DOT 1 (-2125 5000);
DOT 1 (-2125 4950);
DOT 1 (-2125 4900);
DOT 1 (-2125 4750);
DOT 1 (-2125 4700);
DOT 1 (-2125 4650);
DOT 1 (-2125 4550);
DOT 1 (-2125 4600);
DOT 1 (-2125 4500);
DOT 1 (-2125 4400);
DOT 1 (-2125 4450);
DOT 1 (-2125 4300);
DOT 1 (-2125 4350);
DOT 1 (-2125 4250);
DOT 1 (-2125 4200);
DOT 1 (-2125 4150);
DOT 1 (-2125 4050);
DOT 1 (-2125 4100);
DOT 1 (-2125 4000);
DOT 1 (-2125 3950);
DOT 1 (-2125 3900);
DOT 1 (-2125 3850);
DOT 1 (-2125 3800);
DOT 1 (-2125 3750);
DOT 1 (-325 3750);
DOT 1 (-325 3650);
DOT 1 (-325 3700);
DOT 1 (-325 3600);
DOT 1 (-325 3550);
DOT 1 (-325 3500);
DOT 1 (-325 3400);
DOT 1 (-325 3450);
DOT 1 (-325 3350);
DOT 1 (-325 3300);
DOT 1 (-325 3250);
DOT 1 (-325 3150);
DOT 1 (-325 3200);
DOT 1 (-325 3100);
DOT 1 (-325 3050);
DOT 1 (-325 3000);
DOT 1 (-325 2900);
DOT 1 (-325 2950);
DOT 1 (-325 2750);
DOT 1 (-325 2800);
DOT 1 (-325 2850);
DOT 1 (-325 2700);
DOT 1 (-325 2650);
DOT 1 (-325 2600);
DOT 1 (-325 2500);
DOT 1 (-325 2550);
DOT 1 (-325 2450);
DOT 1 (-325 2400);
DOT 1 (-325 2350);
DOT 1 (-325 2250);
DOT 1 (-325 2300);
DOT 1 (-325 2200);
DOT 1 (-325 2150);
DOT 1 (-325 2100);
DOT 1 (-325 2000);
DOT 1 (-325 1900);
DOT 1 (-325 1950);
DOT 1 (-2125 3650);
DOT 1 (-2125 3700);
DOT 1 (-2125 3600);
DOT 1 (-2125 3550);
DOT 1 (-2125 3500);
DOT 1 (-2125 3400);
DOT 1 (-2125 3450);
DOT 1 (-2125 3350);
DOT 1 (-2125 3300);
DOT 1 (-2125 3250);
DOT 1 (-2125 3150);
DOT 1 (-2125 3200);
DOT 1 (-2125 3100);
DOT 1 (-2125 3050);
DOT 1 (-2125 3000);
DOT 1 (-2125 2900);
DOT 1 (-2125 2950);
DOT 1 (-2125 2750);
DOT 1 (-2125 2800);
DOT 1 (-2125 2700);
DOT 1 (-2125 2650);
DOT 1 (-2125 2600);
DOT 1 (-2125 2500);
DOT 1 (-2125 2550);
DOT 1 (-2125 2450);
DOT 1 (-2125 2400);
DOT 1 (-2125 2350);
DOT 1 (-2125 2250);
DOT 1 (-2125 2300);
DOT 1 (-2125 2200);
DOT 1 (-2125 2150);
DOT 1 (-2125 2100);
DOT 1 (-2125 2000);
DOT 1 (-2125 2050);
DOT 1 (-8450 3300);
DOT 1 (-8350 2100);
DOT 1 (-2125 2850);
DOT 1 (-2825 5575);
DOT 1 (-2825 6000);
DOT 1 (-2250 6000);
DOT 1 (-2125 4850);
DOT 1 (-2125 4800);
QUIT
